FILE_TYPE = MACRO_DRAWING;
SET COLOR_WIRE YELLOW;
SET COLOR_PROP MONO;
SET COLOR_DOT WHITE;
SET COLOR_ARC YELLOW;
SET COLOR_BODY GREEN;
SET COLOR_NOTE MONO;
SET PROP_DISPLAY VALUE;
SET PAGE_NUMBER P43;
FORCEADD SCONN288_H44441004..1
(-2400 2750);
FORCEPROP 2 LASTPIN (-2900 2200) $PN 47
J 2
(-2910 2210);
DISPLAY 0.617021 (-2910 2210);
PAINT ORANGE (-2910 2210);
FORCEPROP 2 LASTPIN (-1900 3100) $PN 240
J 0
(-1890 3110);
DISPLAY 0.617021 (-1890 3110);
PAINT ORANGE (-1890 3110);
FORCEPROP 2 LASTPIN (-1900 3150) $PN 102
J 0
(-1890 3160);
DISPLAY 0.617021 (-1890 3160);
PAINT ORANGE (-1890 3160);
FORCEPROP 2 LASTPIN (-2900 3600) $PN 72
J 2
(-2910 3610);
DISPLAY 0.617021 (-2910 3610);
PAINT ORANGE (-2910 3610);
FORCEPROP 2 LASTPIN (-2900 3650) $PN 216
J 2
(-2910 3660);
DISPLAY 0.617021 (-2910 3660);
PAINT ORANGE (-2910 3660);
FORCEPROP 2 LASTPIN (-2900 3750) $PN 214
J 2
(-2910 3760);
DISPLAY 0.617021 (-2910 3760);
PAINT ORANGE (-2910 3760);
FORCEPROP 1 LAST MATERIAL SCONN
J 0
(-2850 4600);
DISPLAY 0.617021 (-2850 4600);
PAINT SKYBLUE (-2850 4600);
FORCEPROP 1 LAST LOCATION J4G1
J 0
(-2850 4650);
DISPLAY 0.617021 (-2850 4650);
PAINT AQUA (-2850 4650);
FORCEPROP 2 LASTPIN (-1900 4200) $PN 282
J 0
(-1890 4210);
DISPLAY 0.617021 (-1890 4210);
PAINT ORANGE (-1890 4210);
FORCEPROP 2 LASTPIN (-2900 3450) $PN 224
J 2
(-2910 3460);
DISPLAY 0.617021 (-2910 3460);
PAINT ORANGE (-2910 3460);
FORCEPROP 2 LASTPIN (-2900 4150) $PN 65
J 2
(-2910 4160);
DISPLAY 0.617021 (-2910 4160);
PAINT ORANGE (-2910 4160);
FORCEPROP 2 LASTPIN (-1900 2900) $PN 242
J 0
(-1890 2910);
DISPLAY 0.617021 (-1890 2910);
PAINT ORANGE (-1890 2910);
FORCEPROP 2 LASTPIN (-2900 4100) $PN 210
J 2
(-2910 4110);
DISPLAY 0.617021 (-2910 4110);
PAINT ORANGE (-2910 4110);
FORCEPROP 2 LASTPIN (-1900 4000) $PN 269
J 0
(-1890 4010);
DISPLAY 0.617021 (-1890 4010);
PAINT ORANGE (-1890 4010);
FORCEPROP 2 LASTPIN (-2900 3550) $PN 79
J 2
(-2910 3560);
DISPLAY 0.617021 (-2910 3560);
PAINT ORANGE (-2910 3560);
FORCEPROP 2 LASTPIN (-2900 3700) $PN 71
J 2
(-2910 3710);
DISPLAY 0.617021 (-2910 3710);
PAINT ORANGE (-2910 3710);
FORCEPROP 2 LASTPIN (-2900 3800) $PN 213
J 2
(-2910 3810);
DISPLAY 0.617021 (-2910 3810);
PAINT ORANGE (-2910 3810);
FORCEPROP 2 LASTPIN (-2900 3850) $PN 69
J 2
(-2910 3860);
DISPLAY 0.617021 (-2910 3860);
PAINT ORANGE (-2910 3860);
FORCEPROP 2 LASTPIN (-2900 3900) $PN 211
J 2
(-2910 3910);
DISPLAY 0.617021 (-2910 3910);
PAINT ORANGE (-2910 3910);
FORCEPROP 2 LASTPIN (-2900 3950) $PN 68
J 2
(-2910 3960);
DISPLAY 0.617021 (-2910 3960);
PAINT ORANGE (-2910 3960);
FORCEPROP 2 LASTPIN (-2900 4000) $PN 66
J 2
(-2910 4010);
DISPLAY 0.617021 (-2910 4010);
PAINT ORANGE (-2910 4010);
FORCEPROP 2 LASTPIN (-2900 4050) $PN 225
J 2
(-2910 4060);
DISPLAY 0.617021 (-2910 4060);
PAINT ORANGE (-2910 4060);
FORCEPROP 2 LASTPIN (-2900 4200) $PN 232
J 2
(-2910 4210);
DISPLAY 0.617021 (-2910 4210);
PAINT ORANGE (-2910 4210);
FORCEPROP 2 LASTPIN (-2900 4250) $PN 228
J 2
(-2910 4260);
DISPLAY 0.617021 (-2910 4260);
PAINT ORANGE (-2910 4260);
FORCEPROP 2 LASTPIN (-2900 4300) $PN 86
J 2
(-2910 4310);
DISPLAY 0.617021 (-2910 4310);
PAINT ORANGE (-2910 4310);
FORCEPROP 2 LASTPIN (-2900 4350) $PN 82
J 2
(-2910 4360);
DISPLAY 0.617021 (-2910 4360);
PAINT ORANGE (-2910 4360);
FORCEPROP 2 LASTPIN (-2900 4400) $PN 234
J 2
(-2910 4410);
DISPLAY 0.617021 (-2910 4410);
PAINT ORANGE (-2910 4410);
FORCEPROP 2 LASTPIN (-2900 1700) $PN 62
J 2
(-2910 1710);
DISPLAY 0.617021 (-2910 1710);
PAINT ORANGE (-2910 1710);
FORCEPROP 2 LASTPIN (-2900 1750) $PN 208
J 2
(-2910 1760);
DISPLAY 0.617021 (-2910 1760);
PAINT ORANGE (-2910 1760);
FORCEPROP 2 LASTPIN (-2900 3400) $PN 81
J 2
(-2910 3410);
DISPLAY 0.617021 (-2910 3410);
PAINT ORANGE (-2910 3410);
FORCEPROP 2 LASTPIN (-2900 3300) $PN 63
J 2
(-2910 3310);
DISPLAY 0.617021 (-2910 3310);
PAINT ORANGE (-2910 3310);
FORCEPROP 2 LASTPIN (-2900 3350) $PN 207
J 2
(-2910 3360);
DISPLAY 0.617021 (-2910 3360);
PAINT ORANGE (-2910 3360);
FORCEPROP 2 LASTPIN (-2900 2950) $PN 235
J 2
(-2910 2960);
DISPLAY 0.617021 (-2910 2960);
PAINT ORANGE (-2910 2960);
FORCEPROP 2 LASTPIN (-2900 2000) $PN 49
J 2
(-2910 2010);
DISPLAY 0.617021 (-2910 2010);
PAINT ORANGE (-2910 2010);
FORCEPROP 2 LASTPIN (-2900 2050) $PN 194
J 2
(-2910 2060);
DISPLAY 0.617021 (-2910 2060);
PAINT ORANGE (-2910 2060);
FORCEPROP 2 LASTPIN (-2900 2100) $PN 56
J 2
(-2910 2110);
DISPLAY 0.617021 (-2910 2110);
PAINT ORANGE (-2910 2110);
FORCEPROP 2 LASTPIN (-2900 2150) $PN 201
J 2
(-2910 2160);
DISPLAY 0.617021 (-2910 2160);
PAINT ORANGE (-2910 2160);
FORCEPROP 2 LASTPIN (-2900 2250) $PN 192
J 2
(-2910 2260);
DISPLAY 0.617021 (-2910 2260);
PAINT ORANGE (-2910 2260);
FORCEPROP 2 LASTPIN (-2900 2300) $PN 54
J 2
(-2910 2310);
DISPLAY 0.617021 (-2910 2310);
PAINT ORANGE (-2910 2310);
FORCEPROP 2 LASTPIN (-2900 2350) $PN 199
J 2
(-2910 2360);
DISPLAY 0.617021 (-2910 2360);
PAINT ORANGE (-2910 2360);
FORCEPROP 2 LASTPIN (-2900 3050) $PN 75
J 2
(-2910 3060);
DISPLAY 0.617021 (-2910 3060);
PAINT ORANGE (-2910 3060);
FORCEPROP 2 LASTPIN (-2900 3100) $PN 74
J 2
(-2910 3110);
DISPLAY 0.617021 (-2910 3110);
PAINT ORANGE (-2910 3110);
FORCEPROP 2 LASTPIN (-2900 3150) $PN 219
J 2
(-2910 3160);
DISPLAY 0.617021 (-2910 3160);
PAINT ORANGE (-2910 3160);
FORCEPROP 2 LASTPIN (-2900 3200) $PN 218
J 2
(-2910 3210);
DISPLAY 0.617021 (-2910 3210);
PAINT ORANGE (-2910 3210);
FORCEPROP 2 LASTPIN (-2900 2600) $PN 60
J 2
(-2910 2610);
DISPLAY 0.617021 (-2910 2610);
PAINT ORANGE (-2910 2610);
FORCEPROP 2 LASTPIN (-2900 2650) $PN 203
J 2
(-2910 2660);
DISPLAY 0.617021 (-2910 2660);
PAINT ORANGE (-2910 2660);
FORCEPROP 2 LASTPIN (-1900 1250) $PN 5
J 0
(-1890 1260);
DISPLAY 0.617021 (-1890 1260);
PAINT ORANGE (-1890 1260);
FORCEPROP 2 LASTPIN (-1900 1300) $PN 150
J 0
(-1890 1310);
DISPLAY 0.617021 (-1890 1310);
PAINT ORANGE (-1890 1310);
FORCEPROP 2 LASTPIN (-1900 1350) $PN 12
J 0
(-1890 1360);
DISPLAY 0.617021 (-1890 1360);
PAINT ORANGE (-1890 1360);
FORCEPROP 2 LASTPIN (-1900 1400) $PN 157
J 0
(-1890 1410);
DISPLAY 0.617021 (-1890 1410);
PAINT ORANGE (-1890 1410);
FORCEPROP 2 LASTPIN (-1900 1450) $PN 3
J 0
(-1890 1460);
DISPLAY 0.617021 (-1890 1460);
PAINT ORANGE (-1890 1460);
FORCEPROP 2 LASTPIN (-1900 1500) $PN 148
J 0
(-1890 1510);
DISPLAY 0.617021 (-1890 1510);
PAINT ORANGE (-1890 1510);
FORCEPROP 2 LASTPIN (-1900 1550) $PN 10
J 0
(-1890 1560);
DISPLAY 0.617021 (-1890 1560);
PAINT ORANGE (-1890 1560);
FORCEPROP 2 LASTPIN (-1900 1600) $PN 155
J 0
(-1890 1610);
DISPLAY 0.617021 (-1890 1610);
PAINT ORANGE (-1890 1610);
FORCEPROP 2 LASTPIN (-1900 1650) $PN 16
J 0
(-1890 1660);
DISPLAY 0.617021 (-1890 1660);
PAINT ORANGE (-1890 1660);
FORCEPROP 2 LASTPIN (-1900 1700) $PN 161
J 0
(-1890 1710);
DISPLAY 0.617021 (-1890 1710);
PAINT ORANGE (-1890 1710);
FORCEPROP 2 LASTPIN (-1900 1750) $PN 23
J 0
(-1890 1760);
DISPLAY 0.617021 (-1890 1760);
PAINT ORANGE (-1890 1760);
FORCEPROP 2 LASTPIN (-1900 1800) $PN 168
J 0
(-1890 1810);
DISPLAY 0.617021 (-1890 1810);
PAINT ORANGE (-1890 1810);
FORCEPROP 2 LASTPIN (-1900 1850) $PN 14
J 0
(-1890 1860);
DISPLAY 0.617021 (-1890 1860);
PAINT ORANGE (-1890 1860);
FORCEPROP 2 LASTPIN (-1900 1900) $PN 159
J 0
(-1890 1910);
DISPLAY 0.617021 (-1890 1910);
PAINT ORANGE (-1890 1910);
FORCEPROP 2 LASTPIN (-1900 1950) $PN 21
J 0
(-1890 1960);
DISPLAY 0.617021 (-1890 1960);
PAINT ORANGE (-1890 1960);
FORCEPROP 2 LASTPIN (-1900 2000) $PN 166
J 0
(-1890 2010);
DISPLAY 0.617021 (-1890 2010);
PAINT ORANGE (-1890 2010);
FORCEPROP 2 LASTPIN (-1900 2050) $PN 27
J 0
(-1890 2060);
DISPLAY 0.617021 (-1890 2060);
PAINT ORANGE (-1890 2060);
FORCEPROP 2 LASTPIN (-1900 2100) $PN 172
J 0
(-1890 2110);
DISPLAY 0.617021 (-1890 2110);
PAINT ORANGE (-1890 2110);
FORCEPROP 2 LASTPIN (-1900 2150) $PN 34
J 0
(-1890 2160);
DISPLAY 0.617021 (-1890 2160);
PAINT ORANGE (-1890 2160);
FORCEPROP 2 LASTPIN (-1900 2200) $PN 179
J 0
(-1890 2210);
DISPLAY 0.617021 (-1890 2210);
PAINT ORANGE (-1890 2210);
FORCEPROP 2 LASTPIN (-1900 2250) $PN 25
J 0
(-1890 2260);
DISPLAY 0.617021 (-1890 2260);
PAINT ORANGE (-1890 2260);
FORCEPROP 2 LASTPIN (-1900 2300) $PN 170
J 0
(-1890 2310);
DISPLAY 0.617021 (-1890 2310);
PAINT ORANGE (-1890 2310);
FORCEPROP 2 LASTPIN (-1900 2350) $PN 32
J 0
(-1890 2360);
DISPLAY 0.617021 (-1890 2360);
PAINT ORANGE (-1890 2360);
FORCEPROP 2 LASTPIN (-1900 2400) $PN 177
J 0
(-1890 2410);
DISPLAY 0.617021 (-1890 2410);
PAINT ORANGE (-1890 2410);
FORCEPROP 2 LASTPIN (-1900 2450) $PN 38
J 0
(-1890 2460);
DISPLAY 0.617021 (-1890 2460);
PAINT ORANGE (-1890 2460);
FORCEPROP 2 LASTPIN (-1900 2500) $PN 183
J 0
(-1890 2510);
DISPLAY 0.617021 (-1890 2510);
PAINT ORANGE (-1890 2510);
FORCEPROP 2 LASTPIN (-1900 2550) $PN 45
J 0
(-1890 2560);
DISPLAY 0.617021 (-1890 2560);
PAINT ORANGE (-1890 2560);
FORCEPROP 2 LASTPIN (-1900 2600) $PN 190
J 0
(-1890 2610);
DISPLAY 0.617021 (-1890 2610);
PAINT ORANGE (-1890 2610);
FORCEPROP 2 LASTPIN (-1900 2650) $PN 36
J 0
(-1890 2660);
DISPLAY 0.617021 (-1890 2660);
PAINT ORANGE (-1890 2660);
FORCEPROP 2 LASTPIN (-1900 2700) $PN 181
J 0
(-1890 2710);
DISPLAY 0.617021 (-1890 2710);
PAINT ORANGE (-1890 2710);
FORCEPROP 2 LASTPIN (-1900 2750) $PN 43
J 0
(-1890 2760);
DISPLAY 0.617021 (-1890 2760);
PAINT ORANGE (-1890 2760);
FORCEPROP 2 LASTPIN (-1900 2800) $PN 188
J 0
(-1890 2810);
DISPLAY 0.617021 (-1890 2810);
PAINT ORANGE (-1890 2810);
FORCEPROP 2 LASTPIN (-1900 2850) $PN 97
J 0
(-1890 2860);
DISPLAY 0.617021 (-1890 2860);
PAINT ORANGE (-1890 2860);
FORCEPROP 2 LASTPIN (-1900 2950) $PN 104
J 0
(-1890 2960);
DISPLAY 0.617021 (-1890 2960);
PAINT ORANGE (-1890 2960);
FORCEPROP 2 LASTPIN (-1900 3000) $PN 249
J 0
(-1890 3010);
DISPLAY 0.617021 (-1890 3010);
PAINT ORANGE (-1890 3010);
FORCEPROP 2 LASTPIN (-1900 3050) $PN 95
J 0
(-1890 3060);
DISPLAY 0.617021 (-1890 3060);
PAINT ORANGE (-1890 3060);
FORCEPROP 2 LASTPIN (-1900 3200) $PN 247
J 0
(-1890 3210);
DISPLAY 0.617021 (-1890 3210);
PAINT ORANGE (-1890 3210);
FORCEPROP 2 LASTPIN (-1900 3250) $PN 108
J 0
(-1890 3260);
DISPLAY 0.617021 (-1890 3260);
PAINT ORANGE (-1890 3260);
FORCEPROP 2 LASTPIN (-1900 3300) $PN 253
J 0
(-1890 3310);
DISPLAY 0.617021 (-1890 3310);
PAINT ORANGE (-1890 3310);
FORCEPROP 2 LASTPIN (-1900 3350) $PN 115
J 0
(-1890 3360);
DISPLAY 0.617021 (-1890 3360);
PAINT ORANGE (-1890 3360);
FORCEPROP 2 LASTPIN (-1900 3400) $PN 260
J 0
(-1890 3410);
DISPLAY 0.617021 (-1890 3410);
PAINT ORANGE (-1890 3410);
FORCEPROP 2 LASTPIN (-1900 3450) $PN 106
J 0
(-1890 3460);
DISPLAY 0.617021 (-1890 3460);
PAINT ORANGE (-1890 3460);
FORCEPROP 2 LASTPIN (-1900 3500) $PN 251
J 0
(-1890 3510);
DISPLAY 0.617021 (-1890 3510);
PAINT ORANGE (-1890 3510);
FORCEPROP 2 LASTPIN (-1900 3550) $PN 113
J 0
(-1890 3560);
DISPLAY 0.617021 (-1890 3560);
PAINT ORANGE (-1890 3560);
FORCEPROP 2 LASTPIN (-1900 3600) $PN 258
J 0
(-1890 3610);
DISPLAY 0.617021 (-1890 3610);
PAINT ORANGE (-1890 3610);
FORCEPROP 2 LASTPIN (-1900 3650) $PN 119
J 0
(-1890 3660);
DISPLAY 0.617021 (-1890 3660);
PAINT ORANGE (-1890 3660);
FORCEPROP 2 LASTPIN (-1900 3700) $PN 264
J 0
(-1890 3710);
DISPLAY 0.617021 (-1890 3710);
PAINT ORANGE (-1890 3710);
FORCEPROP 2 LASTPIN (-1900 3750) $PN 126
J 0
(-1890 3760);
DISPLAY 0.617021 (-1890 3760);
PAINT ORANGE (-1890 3760);
FORCEPROP 2 LASTPIN (-1900 3800) $PN 271
J 0
(-1890 3810);
DISPLAY 0.617021 (-1890 3810);
PAINT ORANGE (-1890 3810);
FORCEPROP 2 LASTPIN (-1900 3850) $PN 117
J 0
(-1890 3860);
DISPLAY 0.617021 (-1890 3860);
PAINT ORANGE (-1890 3860);
FORCEPROP 2 LASTPIN (-1900 3900) $PN 262
J 0
(-1890 3910);
DISPLAY 0.617021 (-1890 3910);
PAINT ORANGE (-1890 3910);
FORCEPROP 2 LASTPIN (-1900 3950) $PN 124
J 0
(-1890 3960);
DISPLAY 0.617021 (-1890 3960);
PAINT ORANGE (-1890 3960);
FORCEPROP 2 LASTPIN (-1900 4050) $PN 130
J 0
(-1890 4060);
DISPLAY 0.617021 (-1890 4060);
PAINT ORANGE (-1890 4060);
FORCEPROP 2 LASTPIN (-1900 4100) $PN 275
J 0
(-1890 4110);
DISPLAY 0.617021 (-1890 4110);
PAINT ORANGE (-1890 4110);
FORCEPROP 2 LASTPIN (-1900 4150) $PN 137
J 0
(-1890 4160);
DISPLAY 0.617021 (-1890 4160);
PAINT ORANGE (-1890 4160);
FORCEPROP 2 LASTPIN (-1900 4250) $PN 128
J 0
(-1890 4260);
DISPLAY 0.617021 (-1890 4260);
PAINT ORANGE (-1890 4260);
FORCEPROP 2 LASTPIN (-1900 4300) $PN 273
J 0
(-1890 4310);
DISPLAY 0.617021 (-1890 4310);
PAINT ORANGE (-1890 4310);
FORCEPROP 2 LASTPIN (-1900 4350) $PN 135
J 0
(-1890 4360);
DISPLAY 0.617021 (-1890 4360);
PAINT ORANGE (-1890 4360);
FORCEPROP 2 LASTPIN (-1900 4400) $PN 280
J 0
(-1890 4410);
DISPLAY 0.617021 (-1890 4410);
PAINT ORANGE (-1890 4410);
FORCEPROP 2 LASTPIN (-2900 1800) $PN 78
J 2
(-2910 1810);
DISPLAY 0.617021 (-2910 1810);
PAINT ORANGE (-2910 1810);
FORCEPROP 2 LASTPIN (-2900 2450) $PN 87
J 2
(-2910 2460);
DISPLAY 0.617021 (-2910 2460);
PAINT ORANGE (-2910 2460);
FORCEPROP 2 LASTPIN (-2900 2500) $PN 91
J 2
(-2910 2510);
DISPLAY 0.617021 (-2910 2510);
PAINT ORANGE (-2910 2510);
FORCEPROP 2 LASTPIN (-2900 1900) $PN 222
J 2
(-2910 1910);
DISPLAY 0.617021 (-2910 1910);
PAINT ORANGE (-2910 1910);
FORCEPROP 2 LASTPIN (-2900 1850) $PN 58
J 2
(-2910 1860);
DISPLAY 0.617021 (-2910 1860);
PAINT ORANGE (-2910 1860);
FORCEPROP 2 LASTPIN (-2900 1050) $PN 205
J 2
(-2910 1060);
DISPLAY 0.617021 (-2910 1060);
PAINT ORANGE (-2910 1060);
FORCEPROP 2 LASTPIN (-2900 1100) $PN 227
J 2
(-2910 1110);
DISPLAY 0.617021 (-2910 1110);
PAINT ORANGE (-2910 1110);
FORCEPROP 2 LASTPIN (-2900 1150) $PN 144
J 2
(-2910 1160);
DISPLAY 0.617021 (-2910 1160);
PAINT ORANGE (-2910 1160);
FORCEPROP 2 LASTPIN (-2900 2750) $PN 84
J 2
(-2910 2760);
DISPLAY 0.617021 (-2910 2760);
PAINT ORANGE (-2910 2760);
FORCEPROP 2 LASTPIN (-2900 2800) $PN 89
J 2
(-2910 2810);
DISPLAY 0.617021 (-2910 2810);
PAINT ORANGE (-2910 2810);
FORCEPROP 2 LASTPIN (-2900 2850) $PN 93
J 2
(-2910 2860);
DISPLAY 0.617021 (-2910 2860);
PAINT ORANGE (-2910 2860);
FORCEPROP 2 LASTPIN (-2900 2900) $PN 237
J 2
(-2910 2910);
DISPLAY 0.617021 (-2910 2910);
PAINT ORANGE (-2910 2910);
FORCEPROP 2 LASTPIN (-2900 1450) $PN 139
J 2
(-2910 1460);
DISPLAY 0.617021 (-2910 1460);
PAINT ORANGE (-2910 1460);
FORCEPROP 2 LASTPIN (-2900 1500) $PN 140
J 2
(-2910 1510);
DISPLAY 0.617021 (-2910 1510);
PAINT ORANGE (-2910 1510);
FORCEPROP 2 LASTPIN (-2900 1550) $PN 238
J 2
(-2910 1560);
DISPLAY 0.617021 (-2910 1560);
PAINT ORANGE (-2910 1560);
FORCEPROP 2 LASTPIN (-2900 950) $PN 230
J 2
(-2910 960);
DISPLAY 0.617021 (-2910 960);
PAINT ORANGE (-2910 960);
FORCEPROP 2 LASTPIN (-2900 1350) $PN 141
J 2
(-2910 1360);
DISPLAY 0.617021 (-2910 1360);
PAINT ORANGE (-2910 1360);
FORCEPROP 2 LASTPIN (-2900 1400) $PN 285
J 2
(-2910 1410);
DISPLAY 0.617021 (-2910 1410);
PAINT ORANGE (-2910 1410);
FORCEPROP 2 LASTPIN (-2900 1600) $PN 284
J 2
(-2910 1610);
DISPLAY 0.617021 (-2910 1610);
PAINT ORANGE (-2910 1610);
FORCEPROP 2 LASTPIN (-2900 1250) $PN 146
J 2
(-2910 1260);
DISPLAY 0.617021 (-2910 1260);
PAINT ORANGE (-2910 1260);
FORCEPROP 1 LAST PART_NUMBER H44441-004
J 0
(-2850 750);
DISPLAY 0.617021 (-2850 750);
PAINT BLUE (-2850 750);
FORCEPROP 2 LAST ROOM DDR4_CH_A
J 0
(-2400 2750);
PAINT ORANGE (-2400 2750);
DISPLAY INVISIBLE (-2400 2750);
FORCEPROP 1 LAST PATH I1
J 0
(-2400 4600);
PAINT GREEN (-2400 4600);
DISPLAY INVISIBLE (-2400 4600);
FORCEPROP 2 LAST CDS_LOCATION J4G1
J 0
(-2850 4650);
DISPLAY 0.617021 (-2850 4650);
PAINT AQUA (-2850 4650);
DISPLAY INVISIBLE (-2850 4650);
FORCEPROP 2 LAST SEC 1
J 0
(-2850 4700);
DISPLAY 0.680851 (-2850 4700);
PAINT MONO (-2850 4700);
DISPLAY INVISIBLE (-2850 4700);
FORCEPROP 2 LAST SEC_TYPE PIP
J 0
(-2850 4700);
DISPLAY 1.021277 (-2850 4700);
PAINT ORANGE (-2850 4700);
DISPLAY INVISIBLE (-2850 4700);
FORCEPROP 2 LAST CDS_LIB mstr_sconn
J 0
(-2400 2750);
PAINT ORANGE (-2400 2750);
DISPLAY INVISIBLE (-2400 2750);
FORCEPROP 2 LAST BOM_COST MEM
J 0
(-2400 2750);
PAINT ORANGE (-2400 2750);
DISPLAY INVISIBLE (-2400 2750);
FORCEPROP 1 LAST PACK_TYPE PIP
J 0
(-2850 4700);
PAINT SKYBLUE (-2850 4700);
DISPLAY INVISIBLE (-2850 4700);
FORCEADD TAP..6
R 2
(-1600 4100);
FORCEPROP 3 LASTPIN (-1650 4100) SIG_NAME M_A_DQ<56>
J 0
(-1640 4110);
DISPLAY 0.659574 (-1640 4110);
PAINT MONO (-1640 4110);
DISPLAY INVISIBLE (-1640 4110);
FORCEPROP 1 LASTPIN (-1650 4100) BN 56
J 2
(-1600 4110);
DISPLAY 0.617021 (-1600 4110);
PAINT PINK (-1600 4110);
FORCEPROP 1 LAST PATH I127
J 2
(-1600 4100);
DISPLAY 0.936170 (-1600 4100);
PAINT GREEN (-1600 4100);
DISPLAY INVISIBLE (-1600 4100);
FORCEPROP 1 LAST HDL_TAP TRUE
J 2
(-1925 3975);
DISPLAY 1.234043 (-1925 3975);
PAINT GREEN (-1925 3975);
DISPLAY INVISIBLE (-1925 3975);
FORCEPROP 1 LAST BODY_TYPE PLUMBING
J 2
(-1600 4050);
DISPLAY 1.234043 (-1600 4050);
PAINT GREEN (-1600 4050);
DISPLAY INVISIBLE (-1600 4050);
FORCEPROP 2 LAST CDS_LIB mstr_standard
J 2
(-1600 4100);
DISPLAY 0.787234 (-1600 4100);
PAINT MONO (-1600 4100);
DISPLAY INVISIBLE (-1600 4100);
FORCEADD TAP..6
R 2
(-1600 4150);
FORCEPROP 3 LASTPIN (-1650 4150) SIG_NAME M_A_DQ<59>
J 0
(-1640 4160);
DISPLAY 0.659574 (-1640 4160);
PAINT MONO (-1640 4160);
DISPLAY INVISIBLE (-1640 4160);
FORCEPROP 1 LASTPIN (-1650 4150) BN 59
J 2
(-1600 4160);
DISPLAY 0.617021 (-1600 4160);
PAINT PINK (-1600 4160);
FORCEPROP 1 LAST PATH I128
J 2
(-1600 4150);
DISPLAY 0.936170 (-1600 4150);
PAINT GREEN (-1600 4150);
DISPLAY INVISIBLE (-1600 4150);
FORCEPROP 1 LAST HDL_TAP TRUE
J 2
(-1925 4025);
DISPLAY 1.234043 (-1925 4025);
PAINT GREEN (-1925 4025);
DISPLAY INVISIBLE (-1925 4025);
FORCEPROP 1 LAST BODY_TYPE PLUMBING
J 2
(-1600 4100);
DISPLAY 1.234043 (-1600 4100);
PAINT GREEN (-1600 4100);
DISPLAY INVISIBLE (-1600 4100);
FORCEPROP 2 LAST CDS_LIB mstr_standard
J 2
(-1600 4150);
DISPLAY 0.787234 (-1600 4150);
PAINT MONO (-1600 4150);
DISPLAY INVISIBLE (-1600 4150);
FORCEADD TAP..6
R 2
(-1600 4200);
FORCEPROP 3 LASTPIN (-1650 4200) SIG_NAME M_A_DQ<58>
J 0
(-1640 4210);
DISPLAY 0.659574 (-1640 4210);
PAINT MONO (-1640 4210);
DISPLAY INVISIBLE (-1640 4210);
FORCEPROP 1 LASTPIN (-1650 4200) BN 58
J 2
(-1600 4210);
DISPLAY 0.617021 (-1600 4210);
PAINT PINK (-1600 4210);
FORCEPROP 1 LAST PATH I129
J 2
(-1600 4200);
DISPLAY 0.936170 (-1600 4200);
PAINT GREEN (-1600 4200);
DISPLAY INVISIBLE (-1600 4200);
FORCEPROP 1 LAST HDL_TAP TRUE
J 2
(-1925 4075);
DISPLAY 1.234043 (-1925 4075);
PAINT GREEN (-1925 4075);
DISPLAY INVISIBLE (-1925 4075);
FORCEPROP 1 LAST BODY_TYPE PLUMBING
J 2
(-1600 4150);
DISPLAY 1.234043 (-1600 4150);
PAINT GREEN (-1600 4150);
DISPLAY INVISIBLE (-1600 4150);
FORCEPROP 2 LAST CDS_LIB mstr_standard
J 2
(-1600 4200);
DISPLAY 0.787234 (-1600 4200);
PAINT MONO (-1600 4200);
DISPLAY INVISIBLE (-1600 4200);
FORCEADD TAP..6
R 2
(-1600 4250);
FORCEPROP 3 LASTPIN (-1650 4250) SIG_NAME M_A_DQ<61>
J 0
(-1640 4260);
DISPLAY 0.659574 (-1640 4260);
PAINT MONO (-1640 4260);
DISPLAY INVISIBLE (-1640 4260);
FORCEPROP 1 LASTPIN (-1650 4250) BN 61
J 2
(-1600 4260);
DISPLAY 0.617021 (-1600 4260);
PAINT PINK (-1600 4260);
FORCEPROP 1 LAST PATH I130
J 2
(-1600 4250);
DISPLAY 0.936170 (-1600 4250);
PAINT GREEN (-1600 4250);
DISPLAY INVISIBLE (-1600 4250);
FORCEPROP 1 LAST HDL_TAP TRUE
J 2
(-1925 4125);
DISPLAY 1.234043 (-1925 4125);
PAINT GREEN (-1925 4125);
DISPLAY INVISIBLE (-1925 4125);
FORCEPROP 1 LAST BODY_TYPE PLUMBING
J 2
(-1600 4200);
DISPLAY 1.234043 (-1600 4200);
PAINT GREEN (-1600 4200);
DISPLAY INVISIBLE (-1600 4200);
FORCEPROP 2 LAST CDS_LIB mstr_standard
J 2
(-1600 4250);
DISPLAY 0.787234 (-1600 4250);
PAINT MONO (-1600 4250);
DISPLAY INVISIBLE (-1600 4250);
FORCEADD TAP..6
R 2
(-1600 4350);
FORCEPROP 3 LASTPIN (-1650 4350) SIG_NAME M_A_DQ<63>
J 0
(-1640 4360);
DISPLAY 0.659574 (-1640 4360);
PAINT MONO (-1640 4360);
DISPLAY INVISIBLE (-1640 4360);
FORCEPROP 1 LASTPIN (-1650 4350) BN 63
J 2
(-1600 4360);
DISPLAY 0.617021 (-1600 4360);
PAINT PINK (-1600 4360);
FORCEPROP 1 LAST PATH I131
J 2
(-1600 4350);
DISPLAY 0.936170 (-1600 4350);
PAINT GREEN (-1600 4350);
DISPLAY INVISIBLE (-1600 4350);
FORCEPROP 1 LAST HDL_TAP TRUE
J 2
(-1925 4225);
DISPLAY 1.234043 (-1925 4225);
PAINT GREEN (-1925 4225);
DISPLAY INVISIBLE (-1925 4225);
FORCEPROP 1 LAST BODY_TYPE PLUMBING
J 2
(-1600 4300);
DISPLAY 1.234043 (-1600 4300);
PAINT GREEN (-1600 4300);
DISPLAY INVISIBLE (-1600 4300);
FORCEPROP 2 LAST CDS_LIB mstr_standard
J 2
(-1600 4350);
DISPLAY 0.787234 (-1600 4350);
PAINT MONO (-1600 4350);
DISPLAY INVISIBLE (-1600 4350);
FORCEADD TAP..6
R 2
(-1600 4300);
FORCEPROP 3 LASTPIN (-1650 4300) SIG_NAME M_A_DQ<60>
J 0
(-1640 4310);
DISPLAY 0.659574 (-1640 4310);
PAINT MONO (-1640 4310);
DISPLAY INVISIBLE (-1640 4310);
FORCEPROP 1 LASTPIN (-1650 4300) BN 60
J 2
(-1600 4310);
DISPLAY 0.617021 (-1600 4310);
PAINT PINK (-1600 4310);
FORCEPROP 1 LAST PATH I132
J 2
(-1600 4300);
DISPLAY 0.936170 (-1600 4300);
PAINT GREEN (-1600 4300);
DISPLAY INVISIBLE (-1600 4300);
FORCEPROP 1 LAST HDL_TAP TRUE
J 2
(-1925 4175);
DISPLAY 1.234043 (-1925 4175);
PAINT GREEN (-1925 4175);
DISPLAY INVISIBLE (-1925 4175);
FORCEPROP 1 LAST BODY_TYPE PLUMBING
J 2
(-1600 4250);
DISPLAY 1.234043 (-1600 4250);
PAINT GREEN (-1600 4250);
DISPLAY INVISIBLE (-1600 4250);
FORCEPROP 2 LAST CDS_LIB mstr_standard
J 2
(-1600 4300);
DISPLAY 0.787234 (-1600 4300);
PAINT MONO (-1600 4300);
DISPLAY INVISIBLE (-1600 4300);
FORCEADD TAP..6
R 2
(-1600 4400);
FORCEPROP 3 LASTPIN (-1650 4400) SIG_NAME M_A_DQ<62>
J 0
(-1640 4410);
DISPLAY 0.659574 (-1640 4410);
PAINT MONO (-1640 4410);
DISPLAY INVISIBLE (-1640 4410);
FORCEPROP 1 LASTPIN (-1650 4400) BN 62
J 2
(-1600 4410);
DISPLAY 0.617021 (-1600 4410);
PAINT PINK (-1600 4410);
FORCEPROP 1 LAST PATH I133
J 2
(-1600 4400);
DISPLAY 0.936170 (-1600 4400);
PAINT GREEN (-1600 4400);
DISPLAY INVISIBLE (-1600 4400);
FORCEPROP 1 LAST HDL_TAP TRUE
J 2
(-1925 4275);
DISPLAY 1.234043 (-1925 4275);
PAINT GREEN (-1925 4275);
DISPLAY INVISIBLE (-1925 4275);
FORCEPROP 1 LAST BODY_TYPE PLUMBING
J 2
(-1600 4350);
DISPLAY 1.234043 (-1600 4350);
PAINT GREEN (-1600 4350);
DISPLAY INVISIBLE (-1600 4350);
FORCEPROP 2 LAST CDS_LIB mstr_standard
J 2
(-1600 4400);
DISPLAY 0.787234 (-1600 4400);
PAINT MONO (-1600 4400);
DISPLAY INVISIBLE (-1600 4400);
FORCEADD TAP..6
R 2
(-1600 3750);
FORCEPROP 3 LASTPIN (-1650 3750) SIG_NAME M_A_DQ<51>
J 0
(-1640 3760);
DISPLAY 0.659574 (-1640 3760);
PAINT MONO (-1640 3760);
DISPLAY INVISIBLE (-1640 3760);
FORCEPROP 1 LASTPIN (-1650 3750) BN 51
J 2
(-1600 3760);
DISPLAY 0.617021 (-1600 3760);
PAINT PINK (-1600 3760);
FORCEPROP 1 LAST PATH I134
J 2
(-1600 3750);
DISPLAY 0.936170 (-1600 3750);
PAINT GREEN (-1600 3750);
DISPLAY INVISIBLE (-1600 3750);
FORCEPROP 1 LAST HDL_TAP TRUE
J 2
(-1925 3625);
DISPLAY 1.234043 (-1925 3625);
PAINT GREEN (-1925 3625);
DISPLAY INVISIBLE (-1925 3625);
FORCEPROP 1 LAST BODY_TYPE PLUMBING
J 2
(-1600 3700);
DISPLAY 1.234043 (-1600 3700);
PAINT GREEN (-1600 3700);
DISPLAY INVISIBLE (-1600 3700);
FORCEPROP 2 LAST CDS_LIB mstr_standard
J 2
(-1600 3750);
DISPLAY 0.787234 (-1600 3750);
PAINT MONO (-1600 3750);
DISPLAY INVISIBLE (-1600 3750);
FORCEADD TAP..6
R 2
(-1600 3800);
FORCEPROP 3 LASTPIN (-1650 3800) SIG_NAME M_A_DQ<50>
J 0
(-1640 3810);
DISPLAY 0.659574 (-1640 3810);
PAINT MONO (-1640 3810);
DISPLAY INVISIBLE (-1640 3810);
FORCEPROP 1 LASTPIN (-1650 3800) BN 50
J 2
(-1600 3810);
DISPLAY 0.617021 (-1600 3810);
PAINT PINK (-1600 3810);
FORCEPROP 1 LAST PATH I135
J 2
(-1600 3800);
DISPLAY 0.936170 (-1600 3800);
PAINT GREEN (-1600 3800);
DISPLAY INVISIBLE (-1600 3800);
FORCEPROP 1 LAST HDL_TAP TRUE
J 2
(-1925 3675);
DISPLAY 1.234043 (-1925 3675);
PAINT GREEN (-1925 3675);
DISPLAY INVISIBLE (-1925 3675);
FORCEPROP 1 LAST BODY_TYPE PLUMBING
J 2
(-1600 3750);
DISPLAY 1.234043 (-1600 3750);
PAINT GREEN (-1600 3750);
DISPLAY INVISIBLE (-1600 3750);
FORCEPROP 2 LAST CDS_LIB mstr_standard
J 2
(-1600 3800);
DISPLAY 0.787234 (-1600 3800);
PAINT MONO (-1600 3800);
DISPLAY INVISIBLE (-1600 3800);
FORCEADD TAP..6
R 2
(-1600 3900);
FORCEPROP 3 LASTPIN (-1650 3900) SIG_NAME M_A_DQ<52>
J 0
(-1640 3910);
DISPLAY 0.659574 (-1640 3910);
PAINT MONO (-1640 3910);
DISPLAY INVISIBLE (-1640 3910);
FORCEPROP 1 LASTPIN (-1650 3900) BN 52
J 2
(-1600 3910);
DISPLAY 0.617021 (-1600 3910);
PAINT PINK (-1600 3910);
FORCEPROP 1 LAST PATH I136
J 2
(-1600 3900);
DISPLAY 0.936170 (-1600 3900);
PAINT GREEN (-1600 3900);
DISPLAY INVISIBLE (-1600 3900);
FORCEPROP 1 LAST HDL_TAP TRUE
J 2
(-1925 3775);
DISPLAY 1.234043 (-1925 3775);
PAINT GREEN (-1925 3775);
DISPLAY INVISIBLE (-1925 3775);
FORCEPROP 1 LAST BODY_TYPE PLUMBING
J 2
(-1600 3850);
DISPLAY 1.234043 (-1600 3850);
PAINT GREEN (-1600 3850);
DISPLAY INVISIBLE (-1600 3850);
FORCEPROP 2 LAST CDS_LIB mstr_standard
J 2
(-1600 3900);
DISPLAY 0.787234 (-1600 3900);
PAINT MONO (-1600 3900);
DISPLAY INVISIBLE (-1600 3900);
FORCEADD TAP..6
R 2
(-1600 3850);
FORCEPROP 3 LASTPIN (-1650 3850) SIG_NAME M_A_DQ<53>
J 0
(-1640 3860);
DISPLAY 0.659574 (-1640 3860);
PAINT MONO (-1640 3860);
DISPLAY INVISIBLE (-1640 3860);
FORCEPROP 1 LASTPIN (-1650 3850) BN 53
J 2
(-1600 3860);
DISPLAY 0.617021 (-1600 3860);
PAINT PINK (-1600 3860);
FORCEPROP 1 LAST PATH I137
J 2
(-1600 3850);
DISPLAY 0.936170 (-1600 3850);
PAINT GREEN (-1600 3850);
DISPLAY INVISIBLE (-1600 3850);
FORCEPROP 1 LAST HDL_TAP TRUE
J 2
(-1925 3725);
DISPLAY 1.234043 (-1925 3725);
PAINT GREEN (-1925 3725);
DISPLAY INVISIBLE (-1925 3725);
FORCEPROP 1 LAST BODY_TYPE PLUMBING
J 2
(-1600 3800);
DISPLAY 1.234043 (-1600 3800);
PAINT GREEN (-1600 3800);
DISPLAY INVISIBLE (-1600 3800);
FORCEPROP 2 LAST CDS_LIB mstr_standard
J 2
(-1600 3850);
DISPLAY 0.787234 (-1600 3850);
PAINT MONO (-1600 3850);
DISPLAY INVISIBLE (-1600 3850);
FORCEADD TAP..6
R 2
(-1600 3950);
FORCEPROP 3 LASTPIN (-1650 3950) SIG_NAME M_A_DQ<55>
J 0
(-1640 3960);
DISPLAY 0.659574 (-1640 3960);
PAINT MONO (-1640 3960);
DISPLAY INVISIBLE (-1640 3960);
FORCEPROP 1 LASTPIN (-1650 3950) BN 55
J 2
(-1600 3960);
DISPLAY 0.617021 (-1600 3960);
PAINT PINK (-1600 3960);
FORCEPROP 1 LAST PATH I138
J 2
(-1600 3950);
DISPLAY 0.936170 (-1600 3950);
PAINT GREEN (-1600 3950);
DISPLAY INVISIBLE (-1600 3950);
FORCEPROP 1 LAST HDL_TAP TRUE
J 2
(-1925 3825);
DISPLAY 1.234043 (-1925 3825);
PAINT GREEN (-1925 3825);
DISPLAY INVISIBLE (-1925 3825);
FORCEPROP 1 LAST BODY_TYPE PLUMBING
J 2
(-1600 3900);
DISPLAY 1.234043 (-1600 3900);
PAINT GREEN (-1600 3900);
DISPLAY INVISIBLE (-1600 3900);
FORCEPROP 2 LAST CDS_LIB mstr_standard
J 2
(-1600 3950);
DISPLAY 0.787234 (-1600 3950);
PAINT MONO (-1600 3950);
DISPLAY INVISIBLE (-1600 3950);
FORCEADD TAP..6
R 2
(-1600 4000);
FORCEPROP 3 LASTPIN (-1650 4000) SIG_NAME M_A_DQ<54>
J 0
(-1640 4010);
DISPLAY 0.659574 (-1640 4010);
PAINT MONO (-1640 4010);
DISPLAY INVISIBLE (-1640 4010);
FORCEPROP 1 LASTPIN (-1650 4000) BN 54
J 2
(-1600 4010);
DISPLAY 0.617021 (-1600 4010);
PAINT PINK (-1600 4010);
FORCEPROP 1 LAST PATH I139
J 2
(-1600 4000);
DISPLAY 0.936170 (-1600 4000);
PAINT GREEN (-1600 4000);
DISPLAY INVISIBLE (-1600 4000);
FORCEPROP 1 LAST HDL_TAP TRUE
J 2
(-1925 3875);
DISPLAY 1.234043 (-1925 3875);
PAINT GREEN (-1925 3875);
DISPLAY INVISIBLE (-1925 3875);
FORCEPROP 1 LAST BODY_TYPE PLUMBING
J 2
(-1600 3950);
DISPLAY 1.234043 (-1600 3950);
PAINT GREEN (-1600 3950);
DISPLAY INVISIBLE (-1600 3950);
FORCEPROP 2 LAST CDS_LIB mstr_standard
J 2
(-1600 4000);
DISPLAY 0.787234 (-1600 4000);
PAINT MONO (-1600 4000);
DISPLAY INVISIBLE (-1600 4000);
FORCEADD TAP..6
R 2
(-1600 4050);
FORCEPROP 3 LASTPIN (-1650 4050) SIG_NAME M_A_DQ<57>
J 0
(-1640 4060);
DISPLAY 0.659574 (-1640 4060);
PAINT MONO (-1640 4060);
DISPLAY INVISIBLE (-1640 4060);
FORCEPROP 1 LASTPIN (-1650 4050) BN 57
J 2
(-1600 4060);
DISPLAY 0.617021 (-1600 4060);
PAINT PINK (-1600 4060);
FORCEPROP 1 LAST PATH I140
J 2
(-1600 4050);
DISPLAY 0.936170 (-1600 4050);
PAINT GREEN (-1600 4050);
DISPLAY INVISIBLE (-1600 4050);
FORCEPROP 1 LAST HDL_TAP TRUE
J 2
(-1925 3925);
DISPLAY 1.234043 (-1925 3925);
PAINT GREEN (-1925 3925);
DISPLAY INVISIBLE (-1925 3925);
FORCEPROP 1 LAST BODY_TYPE PLUMBING
J 2
(-1600 4000);
DISPLAY 1.234043 (-1600 4000);
PAINT GREEN (-1600 4000);
DISPLAY INVISIBLE (-1600 4000);
FORCEPROP 2 LAST CDS_LIB mstr_standard
J 2
(-1600 4050);
DISPLAY 0.787234 (-1600 4050);
PAINT MONO (-1600 4050);
DISPLAY INVISIBLE (-1600 4050);
FORCEADD TAP..6
R 2
(-1600 3700);
FORCEPROP 3 LASTPIN (-1650 3700) SIG_NAME M_A_DQ<48>
J 0
(-1640 3710);
DISPLAY 0.659574 (-1640 3710);
PAINT MONO (-1640 3710);
DISPLAY INVISIBLE (-1640 3710);
FORCEPROP 1 LASTPIN (-1650 3700) BN 48
J 2
(-1600 3710);
DISPLAY 0.617021 (-1600 3710);
PAINT PINK (-1600 3710);
FORCEPROP 1 LAST PATH I141
J 2
(-1600 3700);
DISPLAY 0.936170 (-1600 3700);
PAINT GREEN (-1600 3700);
DISPLAY INVISIBLE (-1600 3700);
FORCEPROP 1 LAST HDL_TAP TRUE
J 2
(-1925 3575);
DISPLAY 1.234043 (-1925 3575);
PAINT GREEN (-1925 3575);
DISPLAY INVISIBLE (-1925 3575);
FORCEPROP 1 LAST BODY_TYPE PLUMBING
J 2
(-1600 3650);
DISPLAY 1.234043 (-1600 3650);
PAINT GREEN (-1600 3650);
DISPLAY INVISIBLE (-1600 3650);
FORCEPROP 2 LAST CDS_LIB mstr_standard
J 2
(-1600 3700);
DISPLAY 0.787234 (-1600 3700);
PAINT MONO (-1600 3700);
DISPLAY INVISIBLE (-1600 3700);
FORCEADD TAP..6
R 2
(-1600 2750);
FORCEPROP 3 LASTPIN (-1650 2750) SIG_NAME M_A_DQ<31>
J 0
(-1640 2760);
DISPLAY 0.659574 (-1640 2760);
PAINT MONO (-1640 2760);
DISPLAY INVISIBLE (-1640 2760);
FORCEPROP 1 LASTPIN (-1650 2750) BN 31
J 2
(-1600 2760);
DISPLAY 0.617021 (-1600 2760);
PAINT PINK (-1600 2760);
FORCEPROP 1 LAST PATH I142
J 2
(-1600 2750);
DISPLAY 0.936170 (-1600 2750);
PAINT GREEN (-1600 2750);
DISPLAY INVISIBLE (-1600 2750);
FORCEPROP 1 LAST HDL_TAP TRUE
J 2
(-1925 2625);
DISPLAY 1.234043 (-1925 2625);
PAINT GREEN (-1925 2625);
DISPLAY INVISIBLE (-1925 2625);
FORCEPROP 1 LAST BODY_TYPE PLUMBING
J 2
(-1600 2700);
DISPLAY 1.234043 (-1600 2700);
PAINT GREEN (-1600 2700);
DISPLAY INVISIBLE (-1600 2700);
FORCEPROP 2 LAST CDS_LIB mstr_standard
J 2
(-1600 2750);
DISPLAY 0.787234 (-1600 2750);
PAINT MONO (-1600 2750);
DISPLAY INVISIBLE (-1600 2750);
FORCEADD TAP..6
R 2
(-1600 2700);
FORCEPROP 3 LASTPIN (-1650 2700) SIG_NAME M_A_DQ<28>
J 0
(-1640 2710);
DISPLAY 0.659574 (-1640 2710);
PAINT MONO (-1640 2710);
DISPLAY INVISIBLE (-1640 2710);
FORCEPROP 1 LASTPIN (-1650 2700) BN 28
J 2
(-1600 2710);
DISPLAY 0.617021 (-1600 2710);
PAINT PINK (-1600 2710);
FORCEPROP 1 LAST PATH I143
J 2
(-1600 2700);
DISPLAY 0.936170 (-1600 2700);
PAINT GREEN (-1600 2700);
DISPLAY INVISIBLE (-1600 2700);
FORCEPROP 1 LAST HDL_TAP TRUE
J 2
(-1925 2575);
DISPLAY 1.234043 (-1925 2575);
PAINT GREEN (-1925 2575);
DISPLAY INVISIBLE (-1925 2575);
FORCEPROP 1 LAST BODY_TYPE PLUMBING
J 2
(-1600 2650);
DISPLAY 1.234043 (-1600 2650);
PAINT GREEN (-1600 2650);
DISPLAY INVISIBLE (-1600 2650);
FORCEPROP 2 LAST CDS_LIB mstr_standard
J 2
(-1600 2700);
DISPLAY 0.787234 (-1600 2700);
PAINT MONO (-1600 2700);
DISPLAY INVISIBLE (-1600 2700);
FORCEADD TAP..6
R 2
(-1600 2800);
FORCEPROP 3 LASTPIN (-1650 2800) SIG_NAME M_A_DQ<30>
J 0
(-1640 2810);
DISPLAY 0.659574 (-1640 2810);
PAINT MONO (-1640 2810);
DISPLAY INVISIBLE (-1640 2810);
FORCEPROP 1 LASTPIN (-1650 2800) BN 30
J 2
(-1600 2810);
DISPLAY 0.617021 (-1600 2810);
PAINT PINK (-1600 2810);
FORCEPROP 1 LAST PATH I144
J 2
(-1600 2800);
DISPLAY 0.936170 (-1600 2800);
PAINT GREEN (-1600 2800);
DISPLAY INVISIBLE (-1600 2800);
FORCEPROP 1 LAST HDL_TAP TRUE
J 2
(-1925 2675);
DISPLAY 1.234043 (-1925 2675);
PAINT GREEN (-1925 2675);
DISPLAY INVISIBLE (-1925 2675);
FORCEPROP 1 LAST BODY_TYPE PLUMBING
J 2
(-1600 2750);
DISPLAY 1.234043 (-1600 2750);
PAINT GREEN (-1600 2750);
DISPLAY INVISIBLE (-1600 2750);
FORCEPROP 2 LAST CDS_LIB mstr_standard
J 2
(-1600 2800);
DISPLAY 0.787234 (-1600 2800);
PAINT MONO (-1600 2800);
DISPLAY INVISIBLE (-1600 2800);
FORCEADD TAP..6
R 2
(-1600 2850);
FORCEPROP 3 LASTPIN (-1650 2850) SIG_NAME M_A_DQ<33>
J 0
(-1640 2860);
DISPLAY 0.659574 (-1640 2860);
PAINT MONO (-1640 2860);
DISPLAY INVISIBLE (-1640 2860);
FORCEPROP 1 LASTPIN (-1650 2850) BN 33
J 2
(-1600 2860);
DISPLAY 0.617021 (-1600 2860);
PAINT PINK (-1600 2860);
FORCEPROP 1 LAST PATH I145
J 2
(-1600 2850);
DISPLAY 0.936170 (-1600 2850);
PAINT GREEN (-1600 2850);
DISPLAY INVISIBLE (-1600 2850);
FORCEPROP 1 LAST HDL_TAP TRUE
J 2
(-1925 2725);
DISPLAY 1.234043 (-1925 2725);
PAINT GREEN (-1925 2725);
DISPLAY INVISIBLE (-1925 2725);
FORCEPROP 1 LAST BODY_TYPE PLUMBING
J 2
(-1600 2800);
DISPLAY 1.234043 (-1600 2800);
PAINT GREEN (-1600 2800);
DISPLAY INVISIBLE (-1600 2800);
FORCEPROP 2 LAST CDS_LIB mstr_standard
J 2
(-1600 2850);
DISPLAY 0.787234 (-1600 2850);
PAINT MONO (-1600 2850);
DISPLAY INVISIBLE (-1600 2850);
FORCEADD TAP..6
R 2
(-1600 2950);
FORCEPROP 3 LASTPIN (-1650 2950) SIG_NAME M_A_DQ<35>
J 0
(-1640 2960);
DISPLAY 0.659574 (-1640 2960);
PAINT MONO (-1640 2960);
DISPLAY INVISIBLE (-1640 2960);
FORCEPROP 1 LASTPIN (-1650 2950) BN 35
J 2
(-1600 2960);
DISPLAY 0.617021 (-1600 2960);
PAINT PINK (-1600 2960);
FORCEPROP 1 LAST PATH I146
J 2
(-1600 2950);
DISPLAY 0.936170 (-1600 2950);
PAINT GREEN (-1600 2950);
DISPLAY INVISIBLE (-1600 2950);
FORCEPROP 1 LAST HDL_TAP TRUE
J 2
(-1925 2825);
DISPLAY 1.234043 (-1925 2825);
PAINT GREEN (-1925 2825);
DISPLAY INVISIBLE (-1925 2825);
FORCEPROP 1 LAST BODY_TYPE PLUMBING
J 2
(-1600 2900);
DISPLAY 1.234043 (-1600 2900);
PAINT GREEN (-1600 2900);
DISPLAY INVISIBLE (-1600 2900);
FORCEPROP 2 LAST CDS_LIB mstr_standard
J 2
(-1600 2950);
DISPLAY 0.787234 (-1600 2950);
PAINT MONO (-1600 2950);
DISPLAY INVISIBLE (-1600 2950);
FORCEADD TAP..6
R 2
(-1600 2900);
FORCEPROP 3 LASTPIN (-1650 2900) SIG_NAME M_A_DQ<32>
J 0
(-1640 2910);
DISPLAY 0.659574 (-1640 2910);
PAINT MONO (-1640 2910);
DISPLAY INVISIBLE (-1640 2910);
FORCEPROP 1 LASTPIN (-1650 2900) BN 32
J 2
(-1600 2910);
DISPLAY 0.617021 (-1600 2910);
PAINT PINK (-1600 2910);
FORCEPROP 1 LAST PATH I147
J 2
(-1600 2900);
DISPLAY 0.936170 (-1600 2900);
PAINT GREEN (-1600 2900);
DISPLAY INVISIBLE (-1600 2900);
FORCEPROP 1 LAST HDL_TAP TRUE
J 2
(-1925 2775);
DISPLAY 1.234043 (-1925 2775);
PAINT GREEN (-1925 2775);
DISPLAY INVISIBLE (-1925 2775);
FORCEPROP 1 LAST BODY_TYPE PLUMBING
J 2
(-1600 2850);
DISPLAY 1.234043 (-1600 2850);
PAINT GREEN (-1600 2850);
DISPLAY INVISIBLE (-1600 2850);
FORCEPROP 2 LAST CDS_LIB mstr_standard
J 2
(-1600 2900);
DISPLAY 0.787234 (-1600 2900);
PAINT MONO (-1600 2900);
DISPLAY INVISIBLE (-1600 2900);
FORCEADD TAP..6
R 2
(-1600 3000);
FORCEPROP 3 LASTPIN (-1650 3000) SIG_NAME M_A_DQ<34>
J 0
(-1640 3010);
DISPLAY 0.659574 (-1640 3010);
PAINT MONO (-1640 3010);
DISPLAY INVISIBLE (-1640 3010);
FORCEPROP 1 LASTPIN (-1650 3000) BN 34
J 2
(-1600 3010);
DISPLAY 0.617021 (-1600 3010);
PAINT PINK (-1600 3010);
FORCEPROP 1 LAST PATH I148
J 2
(-1600 3000);
DISPLAY 0.936170 (-1600 3000);
PAINT GREEN (-1600 3000);
DISPLAY INVISIBLE (-1600 3000);
FORCEPROP 1 LAST HDL_TAP TRUE
J 2
(-1925 2875);
DISPLAY 1.234043 (-1925 2875);
PAINT GREEN (-1925 2875);
DISPLAY INVISIBLE (-1925 2875);
FORCEPROP 1 LAST BODY_TYPE PLUMBING
J 2
(-1600 2950);
DISPLAY 1.234043 (-1600 2950);
PAINT GREEN (-1600 2950);
DISPLAY INVISIBLE (-1600 2950);
FORCEPROP 2 LAST CDS_LIB mstr_standard
J 2
(-1600 3000);
DISPLAY 0.787234 (-1600 3000);
PAINT MONO (-1600 3000);
DISPLAY INVISIBLE (-1600 3000);
FORCEADD TAP..6
R 2
(-1600 3050);
FORCEPROP 3 LASTPIN (-1650 3050) SIG_NAME M_A_DQ<37>
J 0
(-1640 3060);
DISPLAY 0.659574 (-1640 3060);
PAINT MONO (-1640 3060);
DISPLAY INVISIBLE (-1640 3060);
FORCEPROP 1 LASTPIN (-1650 3050) BN 37
J 2
(-1600 3060);
DISPLAY 0.617021 (-1600 3060);
PAINT PINK (-1600 3060);
FORCEPROP 1 LAST PATH I149
J 2
(-1600 3050);
DISPLAY 0.936170 (-1600 3050);
PAINT GREEN (-1600 3050);
DISPLAY INVISIBLE (-1600 3050);
FORCEPROP 1 LAST HDL_TAP TRUE
J 2
(-1925 2925);
DISPLAY 1.234043 (-1925 2925);
PAINT GREEN (-1925 2925);
DISPLAY INVISIBLE (-1925 2925);
FORCEPROP 1 LAST BODY_TYPE PLUMBING
J 2
(-1600 3000);
DISPLAY 1.234043 (-1600 3000);
PAINT GREEN (-1600 3000);
DISPLAY INVISIBLE (-1600 3000);
FORCEPROP 2 LAST CDS_LIB mstr_standard
J 2
(-1600 3050);
DISPLAY 0.787234 (-1600 3050);
PAINT MONO (-1600 3050);
DISPLAY INVISIBLE (-1600 3050);
FORCEADD TAP..6
R 2
(-1600 3100);
FORCEPROP 3 LASTPIN (-1650 3100) SIG_NAME M_A_DQ<36>
J 0
(-1640 3110);
DISPLAY 0.659574 (-1640 3110);
PAINT MONO (-1640 3110);
DISPLAY INVISIBLE (-1640 3110);
FORCEPROP 1 LASTPIN (-1650 3100) BN 36
J 2
(-1600 3110);
DISPLAY 0.617021 (-1600 3110);
PAINT PINK (-1600 3110);
FORCEPROP 1 LAST PATH I150
J 2
(-1600 3100);
DISPLAY 0.936170 (-1600 3100);
PAINT GREEN (-1600 3100);
DISPLAY INVISIBLE (-1600 3100);
FORCEPROP 1 LAST HDL_TAP TRUE
J 2
(-1925 2975);
DISPLAY 1.234043 (-1925 2975);
PAINT GREEN (-1925 2975);
DISPLAY INVISIBLE (-1925 2975);
FORCEPROP 1 LAST BODY_TYPE PLUMBING
J 2
(-1600 3050);
DISPLAY 1.234043 (-1600 3050);
PAINT GREEN (-1600 3050);
DISPLAY INVISIBLE (-1600 3050);
FORCEPROP 2 LAST CDS_LIB mstr_standard
J 2
(-1600 3100);
DISPLAY 0.787234 (-1600 3100);
PAINT MONO (-1600 3100);
DISPLAY INVISIBLE (-1600 3100);
FORCEADD TAP..6
R 2
(-1600 3200);
FORCEPROP 3 LASTPIN (-1650 3200) SIG_NAME M_A_DQ<38>
J 0
(-1640 3210);
DISPLAY 0.659574 (-1640 3210);
PAINT MONO (-1640 3210);
DISPLAY INVISIBLE (-1640 3210);
FORCEPROP 1 LASTPIN (-1650 3200) BN 38
J 2
(-1600 3210);
DISPLAY 0.617021 (-1600 3210);
PAINT PINK (-1600 3210);
FORCEPROP 1 LAST PATH I151
J 2
(-1600 3200);
DISPLAY 0.936170 (-1600 3200);
PAINT GREEN (-1600 3200);
DISPLAY INVISIBLE (-1600 3200);
FORCEPROP 1 LAST HDL_TAP TRUE
J 2
(-1925 3075);
DISPLAY 1.234043 (-1925 3075);
PAINT GREEN (-1925 3075);
DISPLAY INVISIBLE (-1925 3075);
FORCEPROP 1 LAST BODY_TYPE PLUMBING
J 2
(-1600 3150);
DISPLAY 1.234043 (-1600 3150);
PAINT GREEN (-1600 3150);
DISPLAY INVISIBLE (-1600 3150);
FORCEPROP 2 LAST CDS_LIB mstr_standard
J 2
(-1600 3200);
DISPLAY 0.787234 (-1600 3200);
PAINT MONO (-1600 3200);
DISPLAY INVISIBLE (-1600 3200);
FORCEADD TAP..6
R 2
(-1600 3150);
FORCEPROP 3 LASTPIN (-1650 3150) SIG_NAME M_A_DQ<39>
J 0
(-1640 3160);
DISPLAY 0.659574 (-1640 3160);
PAINT MONO (-1640 3160);
DISPLAY INVISIBLE (-1640 3160);
FORCEPROP 1 LASTPIN (-1650 3150) BN 39
J 2
(-1600 3160);
DISPLAY 0.617021 (-1600 3160);
PAINT PINK (-1600 3160);
FORCEPROP 1 LAST PATH I152
J 2
(-1600 3150);
DISPLAY 0.936170 (-1600 3150);
PAINT GREEN (-1600 3150);
DISPLAY INVISIBLE (-1600 3150);
FORCEPROP 1 LAST HDL_TAP TRUE
J 2
(-1925 3025);
DISPLAY 1.234043 (-1925 3025);
PAINT GREEN (-1925 3025);
DISPLAY INVISIBLE (-1925 3025);
FORCEPROP 1 LAST BODY_TYPE PLUMBING
J 2
(-1600 3100);
DISPLAY 1.234043 (-1600 3100);
PAINT GREEN (-1600 3100);
DISPLAY INVISIBLE (-1600 3100);
FORCEPROP 2 LAST CDS_LIB mstr_standard
J 2
(-1600 3150);
DISPLAY 0.787234 (-1600 3150);
PAINT MONO (-1600 3150);
DISPLAY INVISIBLE (-1600 3150);
FORCEADD TAP..6
R 2
(-1600 3250);
FORCEPROP 3 LASTPIN (-1650 3250) SIG_NAME M_A_DQ<41>
J 0
(-1640 3260);
DISPLAY 0.659574 (-1640 3260);
PAINT MONO (-1640 3260);
DISPLAY INVISIBLE (-1640 3260);
FORCEPROP 1 LASTPIN (-1650 3250) BN 41
J 2
(-1600 3260);
DISPLAY 0.617021 (-1600 3260);
PAINT PINK (-1600 3260);
FORCEPROP 1 LAST PATH I153
J 2
(-1600 3250);
DISPLAY 0.936170 (-1600 3250);
PAINT GREEN (-1600 3250);
DISPLAY INVISIBLE (-1600 3250);
FORCEPROP 1 LAST HDL_TAP TRUE
J 2
(-1925 3125);
DISPLAY 1.234043 (-1925 3125);
PAINT GREEN (-1925 3125);
DISPLAY INVISIBLE (-1925 3125);
FORCEPROP 1 LAST BODY_TYPE PLUMBING
J 2
(-1600 3200);
DISPLAY 1.234043 (-1600 3200);
PAINT GREEN (-1600 3200);
DISPLAY INVISIBLE (-1600 3200);
FORCEPROP 2 LAST CDS_LIB mstr_standard
J 2
(-1600 3250);
DISPLAY 0.787234 (-1600 3250);
PAINT MONO (-1600 3250);
DISPLAY INVISIBLE (-1600 3250);
FORCEADD TAP..6
R 2
(-1600 3300);
FORCEPROP 3 LASTPIN (-1650 3300) SIG_NAME M_A_DQ<40>
J 0
(-1640 3310);
DISPLAY 0.659574 (-1640 3310);
PAINT MONO (-1640 3310);
DISPLAY INVISIBLE (-1640 3310);
FORCEPROP 1 LASTPIN (-1650 3300) BN 40
J 2
(-1600 3310);
DISPLAY 0.617021 (-1600 3310);
PAINT PINK (-1600 3310);
FORCEPROP 1 LAST PATH I154
J 2
(-1600 3300);
DISPLAY 0.936170 (-1600 3300);
PAINT GREEN (-1600 3300);
DISPLAY INVISIBLE (-1600 3300);
FORCEPROP 1 LAST HDL_TAP TRUE
J 2
(-1925 3175);
DISPLAY 1.234043 (-1925 3175);
PAINT GREEN (-1925 3175);
DISPLAY INVISIBLE (-1925 3175);
FORCEPROP 1 LAST BODY_TYPE PLUMBING
J 2
(-1600 3250);
DISPLAY 1.234043 (-1600 3250);
PAINT GREEN (-1600 3250);
DISPLAY INVISIBLE (-1600 3250);
FORCEPROP 2 LAST CDS_LIB mstr_standard
J 2
(-1600 3300);
DISPLAY 0.787234 (-1600 3300);
PAINT MONO (-1600 3300);
DISPLAY INVISIBLE (-1600 3300);
FORCEADD TAP..6
R 2
(-1600 3350);
FORCEPROP 3 LASTPIN (-1650 3350) SIG_NAME M_A_DQ<43>
J 0
(-1640 3360);
DISPLAY 0.659574 (-1640 3360);
PAINT MONO (-1640 3360);
DISPLAY INVISIBLE (-1640 3360);
FORCEPROP 1 LASTPIN (-1650 3350) BN 43
J 2
(-1600 3360);
DISPLAY 0.617021 (-1600 3360);
PAINT PINK (-1600 3360);
FORCEPROP 1 LAST PATH I155
J 2
(-1600 3350);
DISPLAY 0.936170 (-1600 3350);
PAINT GREEN (-1600 3350);
DISPLAY INVISIBLE (-1600 3350);
FORCEPROP 1 LAST HDL_TAP TRUE
J 2
(-1925 3225);
DISPLAY 1.234043 (-1925 3225);
PAINT GREEN (-1925 3225);
DISPLAY INVISIBLE (-1925 3225);
FORCEPROP 1 LAST BODY_TYPE PLUMBING
J 2
(-1600 3300);
DISPLAY 1.234043 (-1600 3300);
PAINT GREEN (-1600 3300);
DISPLAY INVISIBLE (-1600 3300);
FORCEPROP 2 LAST CDS_LIB mstr_standard
J 2
(-1600 3350);
DISPLAY 0.787234 (-1600 3350);
PAINT MONO (-1600 3350);
DISPLAY INVISIBLE (-1600 3350);
FORCEADD TAP..6
R 2
(-1600 3450);
FORCEPROP 3 LASTPIN (-1650 3450) SIG_NAME M_A_DQ<45>
J 0
(-1640 3460);
DISPLAY 0.659574 (-1640 3460);
PAINT MONO (-1640 3460);
DISPLAY INVISIBLE (-1640 3460);
FORCEPROP 1 LASTPIN (-1650 3450) BN 45
J 2
(-1600 3460);
DISPLAY 0.617021 (-1600 3460);
PAINT PINK (-1600 3460);
FORCEPROP 1 LAST PATH I156
J 2
(-1600 3450);
DISPLAY 0.936170 (-1600 3450);
PAINT GREEN (-1600 3450);
DISPLAY INVISIBLE (-1600 3450);
FORCEPROP 1 LAST HDL_TAP TRUE
J 2
(-1925 3325);
DISPLAY 1.234043 (-1925 3325);
PAINT GREEN (-1925 3325);
DISPLAY INVISIBLE (-1925 3325);
FORCEPROP 1 LAST BODY_TYPE PLUMBING
J 2
(-1600 3400);
DISPLAY 1.234043 (-1600 3400);
PAINT GREEN (-1600 3400);
DISPLAY INVISIBLE (-1600 3400);
FORCEPROP 2 LAST CDS_LIB mstr_standard
J 2
(-1600 3450);
DISPLAY 0.787234 (-1600 3450);
PAINT MONO (-1600 3450);
DISPLAY INVISIBLE (-1600 3450);
FORCEADD TAP..6
R 2
(-1600 3400);
FORCEPROP 3 LASTPIN (-1650 3400) SIG_NAME M_A_DQ<42>
J 0
(-1640 3410);
DISPLAY 0.659574 (-1640 3410);
PAINT MONO (-1640 3410);
DISPLAY INVISIBLE (-1640 3410);
FORCEPROP 1 LASTPIN (-1650 3400) BN 42
J 2
(-1600 3410);
DISPLAY 0.617021 (-1600 3410);
PAINT PINK (-1600 3410);
FORCEPROP 1 LAST PATH I157
J 2
(-1600 3400);
DISPLAY 0.936170 (-1600 3400);
PAINT GREEN (-1600 3400);
DISPLAY INVISIBLE (-1600 3400);
FORCEPROP 1 LAST HDL_TAP TRUE
J 2
(-1925 3275);
DISPLAY 1.234043 (-1925 3275);
PAINT GREEN (-1925 3275);
DISPLAY INVISIBLE (-1925 3275);
FORCEPROP 1 LAST BODY_TYPE PLUMBING
J 2
(-1600 3350);
DISPLAY 1.234043 (-1600 3350);
PAINT GREEN (-1600 3350);
DISPLAY INVISIBLE (-1600 3350);
FORCEPROP 2 LAST CDS_LIB mstr_standard
J 2
(-1600 3400);
DISPLAY 0.787234 (-1600 3400);
PAINT MONO (-1600 3400);
DISPLAY INVISIBLE (-1600 3400);
FORCEADD TAP..6
R 2
(-1600 3500);
FORCEPROP 3 LASTPIN (-1650 3500) SIG_NAME M_A_DQ<44>
J 0
(-1640 3510);
DISPLAY 0.659574 (-1640 3510);
PAINT MONO (-1640 3510);
DISPLAY INVISIBLE (-1640 3510);
FORCEPROP 1 LASTPIN (-1650 3500) BN 44
J 2
(-1600 3510);
DISPLAY 0.617021 (-1600 3510);
PAINT PINK (-1600 3510);
FORCEPROP 1 LAST PATH I158
J 2
(-1600 3500);
DISPLAY 0.936170 (-1600 3500);
PAINT GREEN (-1600 3500);
DISPLAY INVISIBLE (-1600 3500);
FORCEPROP 1 LAST HDL_TAP TRUE
J 2
(-1925 3375);
DISPLAY 1.234043 (-1925 3375);
PAINT GREEN (-1925 3375);
DISPLAY INVISIBLE (-1925 3375);
FORCEPROP 1 LAST BODY_TYPE PLUMBING
J 2
(-1600 3450);
DISPLAY 1.234043 (-1600 3450);
PAINT GREEN (-1600 3450);
DISPLAY INVISIBLE (-1600 3450);
FORCEPROP 2 LAST CDS_LIB mstr_standard
J 2
(-1600 3500);
DISPLAY 0.787234 (-1600 3500);
PAINT MONO (-1600 3500);
DISPLAY INVISIBLE (-1600 3500);
FORCEADD TAP..6
R 2
(-1600 3550);
FORCEPROP 3 LASTPIN (-1650 3550) SIG_NAME M_A_DQ<47>
J 0
(-1640 3560);
DISPLAY 0.659574 (-1640 3560);
PAINT MONO (-1640 3560);
DISPLAY INVISIBLE (-1640 3560);
FORCEPROP 1 LASTPIN (-1650 3550) BN 47
J 2
(-1600 3560);
DISPLAY 0.617021 (-1600 3560);
PAINT PINK (-1600 3560);
FORCEPROP 1 LAST PATH I159
J 2
(-1600 3550);
DISPLAY 0.936170 (-1600 3550);
PAINT GREEN (-1600 3550);
DISPLAY INVISIBLE (-1600 3550);
FORCEPROP 1 LAST HDL_TAP TRUE
J 2
(-1925 3425);
DISPLAY 1.234043 (-1925 3425);
PAINT GREEN (-1925 3425);
DISPLAY INVISIBLE (-1925 3425);
FORCEPROP 1 LAST BODY_TYPE PLUMBING
J 2
(-1600 3500);
DISPLAY 1.234043 (-1600 3500);
PAINT GREEN (-1600 3500);
DISPLAY INVISIBLE (-1600 3500);
FORCEPROP 2 LAST CDS_LIB mstr_standard
J 2
(-1600 3550);
DISPLAY 0.787234 (-1600 3550);
PAINT MONO (-1600 3550);
DISPLAY INVISIBLE (-1600 3550);
FORCEADD TAP..6
R 2
(-1600 3650);
FORCEPROP 3 LASTPIN (-1650 3650) SIG_NAME M_A_DQ<49>
J 0
(-1640 3660);
DISPLAY 0.659574 (-1640 3660);
PAINT MONO (-1640 3660);
DISPLAY INVISIBLE (-1640 3660);
FORCEPROP 1 LASTPIN (-1650 3650) BN 49
J 2
(-1600 3660);
DISPLAY 0.617021 (-1600 3660);
PAINT PINK (-1600 3660);
FORCEPROP 1 LAST PATH I160
J 2
(-1600 3650);
DISPLAY 0.936170 (-1600 3650);
PAINT GREEN (-1600 3650);
DISPLAY INVISIBLE (-1600 3650);
FORCEPROP 1 LAST HDL_TAP TRUE
J 2
(-1925 3525);
DISPLAY 1.234043 (-1925 3525);
PAINT GREEN (-1925 3525);
DISPLAY INVISIBLE (-1925 3525);
FORCEPROP 1 LAST BODY_TYPE PLUMBING
J 2
(-1600 3600);
DISPLAY 1.234043 (-1600 3600);
PAINT GREEN (-1600 3600);
DISPLAY INVISIBLE (-1600 3600);
FORCEPROP 2 LAST CDS_LIB mstr_standard
J 2
(-1600 3650);
DISPLAY 0.787234 (-1600 3650);
PAINT MONO (-1600 3650);
DISPLAY INVISIBLE (-1600 3650);
FORCEADD TAP..6
R 2
(-1600 3600);
FORCEPROP 3 LASTPIN (-1650 3600) SIG_NAME M_A_DQ<46>
J 0
(-1640 3610);
DISPLAY 0.659574 (-1640 3610);
PAINT MONO (-1640 3610);
DISPLAY INVISIBLE (-1640 3610);
FORCEPROP 1 LASTPIN (-1650 3600) BN 46
J 2
(-1600 3610);
DISPLAY 0.617021 (-1600 3610);
PAINT PINK (-1600 3610);
FORCEPROP 1 LAST PATH I161
J 2
(-1600 3600);
DISPLAY 0.936170 (-1600 3600);
PAINT GREEN (-1600 3600);
DISPLAY INVISIBLE (-1600 3600);
FORCEPROP 1 LAST HDL_TAP TRUE
J 2
(-1925 3475);
DISPLAY 1.234043 (-1925 3475);
PAINT GREEN (-1925 3475);
DISPLAY INVISIBLE (-1925 3475);
FORCEPROP 1 LAST BODY_TYPE PLUMBING
J 2
(-1600 3550);
DISPLAY 1.234043 (-1600 3550);
PAINT GREEN (-1600 3550);
DISPLAY INVISIBLE (-1600 3550);
FORCEPROP 2 LAST CDS_LIB mstr_standard
J 2
(-1600 3600);
DISPLAY 0.787234 (-1600 3600);
PAINT MONO (-1600 3600);
DISPLAY INVISIBLE (-1600 3600);
FORCEADD TAP..6
R 2
(-1600 2050);
FORCEPROP 3 LASTPIN (-1650 2050) SIG_NAME M_A_DQ<17>
J 0
(-1640 2060);
DISPLAY 0.659574 (-1640 2060);
PAINT MONO (-1640 2060);
DISPLAY INVISIBLE (-1640 2060);
FORCEPROP 1 LASTPIN (-1650 2050) BN 17
J 2
(-1600 2060);
DISPLAY 0.617021 (-1600 2060);
PAINT PINK (-1600 2060);
FORCEPROP 1 LAST PATH I162
J 2
(-1600 2050);
DISPLAY 0.936170 (-1600 2050);
PAINT GREEN (-1600 2050);
DISPLAY INVISIBLE (-1600 2050);
FORCEPROP 1 LAST HDL_TAP TRUE
J 2
(-1925 1925);
DISPLAY 1.234043 (-1925 1925);
PAINT GREEN (-1925 1925);
DISPLAY INVISIBLE (-1925 1925);
FORCEPROP 1 LAST BODY_TYPE PLUMBING
J 2
(-1600 2000);
DISPLAY 1.234043 (-1600 2000);
PAINT GREEN (-1600 2000);
DISPLAY INVISIBLE (-1600 2000);
FORCEPROP 2 LAST CDS_LIB mstr_standard
J 2
(-1600 2050);
DISPLAY 0.787234 (-1600 2050);
PAINT MONO (-1600 2050);
DISPLAY INVISIBLE (-1600 2050);
FORCEADD TAP..6
R 2
(-1600 2000);
FORCEPROP 3 LASTPIN (-1650 2000) SIG_NAME M_A_DQ<14>
J 0
(-1640 2010);
DISPLAY 0.659574 (-1640 2010);
PAINT MONO (-1640 2010);
DISPLAY INVISIBLE (-1640 2010);
FORCEPROP 1 LASTPIN (-1650 2000) BN 14
J 2
(-1600 2010);
DISPLAY 0.617021 (-1600 2010);
PAINT PINK (-1600 2010);
FORCEPROP 1 LAST PATH I163
J 2
(-1600 2000);
DISPLAY 0.936170 (-1600 2000);
PAINT GREEN (-1600 2000);
DISPLAY INVISIBLE (-1600 2000);
FORCEPROP 1 LAST HDL_TAP TRUE
J 2
(-1925 1875);
DISPLAY 1.234043 (-1925 1875);
PAINT GREEN (-1925 1875);
DISPLAY INVISIBLE (-1925 1875);
FORCEPROP 1 LAST BODY_TYPE PLUMBING
J 2
(-1600 1950);
DISPLAY 1.234043 (-1600 1950);
PAINT GREEN (-1600 1950);
DISPLAY INVISIBLE (-1600 1950);
FORCEPROP 2 LAST CDS_LIB mstr_standard
J 2
(-1600 2000);
DISPLAY 0.787234 (-1600 2000);
PAINT MONO (-1600 2000);
DISPLAY INVISIBLE (-1600 2000);
FORCEADD TAP..6
R 2
(-1600 2100);
FORCEPROP 3 LASTPIN (-1650 2100) SIG_NAME M_A_DQ<16>
J 0
(-1640 2110);
DISPLAY 0.659574 (-1640 2110);
PAINT MONO (-1640 2110);
DISPLAY INVISIBLE (-1640 2110);
FORCEPROP 1 LASTPIN (-1650 2100) BN 16
J 2
(-1600 2110);
DISPLAY 0.617021 (-1600 2110);
PAINT PINK (-1600 2110);
FORCEPROP 1 LAST PATH I164
J 2
(-1600 2100);
DISPLAY 0.936170 (-1600 2100);
PAINT GREEN (-1600 2100);
DISPLAY INVISIBLE (-1600 2100);
FORCEPROP 1 LAST HDL_TAP TRUE
J 2
(-1925 1975);
DISPLAY 1.234043 (-1925 1975);
PAINT GREEN (-1925 1975);
DISPLAY INVISIBLE (-1925 1975);
FORCEPROP 1 LAST BODY_TYPE PLUMBING
J 2
(-1600 2050);
DISPLAY 1.234043 (-1600 2050);
PAINT GREEN (-1600 2050);
DISPLAY INVISIBLE (-1600 2050);
FORCEPROP 2 LAST CDS_LIB mstr_standard
J 2
(-1600 2100);
DISPLAY 0.787234 (-1600 2100);
PAINT MONO (-1600 2100);
DISPLAY INVISIBLE (-1600 2100);
FORCEADD TAP..6
R 2
(-1600 2150);
FORCEPROP 3 LASTPIN (-1650 2150) SIG_NAME M_A_DQ<19>
J 0
(-1640 2160);
DISPLAY 0.659574 (-1640 2160);
PAINT MONO (-1640 2160);
DISPLAY INVISIBLE (-1640 2160);
FORCEPROP 1 LASTPIN (-1650 2150) BN 19
J 2
(-1600 2160);
DISPLAY 0.617021 (-1600 2160);
PAINT PINK (-1600 2160);
FORCEPROP 1 LAST PATH I165
J 2
(-1600 2150);
DISPLAY 0.936170 (-1600 2150);
PAINT GREEN (-1600 2150);
DISPLAY INVISIBLE (-1600 2150);
FORCEPROP 1 LAST HDL_TAP TRUE
J 2
(-1925 2025);
DISPLAY 1.234043 (-1925 2025);
PAINT GREEN (-1925 2025);
DISPLAY INVISIBLE (-1925 2025);
FORCEPROP 1 LAST BODY_TYPE PLUMBING
J 2
(-1600 2100);
DISPLAY 1.234043 (-1600 2100);
PAINT GREEN (-1600 2100);
DISPLAY INVISIBLE (-1600 2100);
FORCEPROP 2 LAST CDS_LIB mstr_standard
J 2
(-1600 2150);
DISPLAY 0.787234 (-1600 2150);
PAINT MONO (-1600 2150);
DISPLAY INVISIBLE (-1600 2150);
FORCEADD TAP..6
R 2
(-1600 2200);
FORCEPROP 3 LASTPIN (-1650 2200) SIG_NAME M_A_DQ<18>
J 0
(-1640 2210);
DISPLAY 0.659574 (-1640 2210);
PAINT MONO (-1640 2210);
DISPLAY INVISIBLE (-1640 2210);
FORCEPROP 1 LASTPIN (-1650 2200) BN 18
J 2
(-1600 2210);
DISPLAY 0.617021 (-1600 2210);
PAINT PINK (-1600 2210);
FORCEPROP 1 LAST PATH I166
J 2
(-1600 2200);
DISPLAY 0.936170 (-1600 2200);
PAINT GREEN (-1600 2200);
DISPLAY INVISIBLE (-1600 2200);
FORCEPROP 1 LAST HDL_TAP TRUE
J 2
(-1925 2075);
DISPLAY 1.234043 (-1925 2075);
PAINT GREEN (-1925 2075);
DISPLAY INVISIBLE (-1925 2075);
FORCEPROP 1 LAST BODY_TYPE PLUMBING
J 2
(-1600 2150);
DISPLAY 1.234043 (-1600 2150);
PAINT GREEN (-1600 2150);
DISPLAY INVISIBLE (-1600 2150);
FORCEPROP 2 LAST CDS_LIB mstr_standard
J 2
(-1600 2200);
DISPLAY 0.787234 (-1600 2200);
PAINT MONO (-1600 2200);
DISPLAY INVISIBLE (-1600 2200);
FORCEADD TAP..6
R 2
(-1600 2300);
FORCEPROP 3 LASTPIN (-1650 2300) SIG_NAME M_A_DQ<20>
J 0
(-1640 2310);
DISPLAY 0.659574 (-1640 2310);
PAINT MONO (-1640 2310);
DISPLAY INVISIBLE (-1640 2310);
FORCEPROP 1 LASTPIN (-1650 2300) BN 20
J 2
(-1600 2310);
DISPLAY 0.617021 (-1600 2310);
PAINT PINK (-1600 2310);
FORCEPROP 1 LAST PATH I167
J 2
(-1600 2300);
DISPLAY 0.936170 (-1600 2300);
PAINT GREEN (-1600 2300);
DISPLAY INVISIBLE (-1600 2300);
FORCEPROP 1 LAST HDL_TAP TRUE
J 2
(-1925 2175);
DISPLAY 1.234043 (-1925 2175);
PAINT GREEN (-1925 2175);
DISPLAY INVISIBLE (-1925 2175);
FORCEPROP 1 LAST BODY_TYPE PLUMBING
J 2
(-1600 2250);
DISPLAY 1.234043 (-1600 2250);
PAINT GREEN (-1600 2250);
DISPLAY INVISIBLE (-1600 2250);
FORCEPROP 2 LAST CDS_LIB mstr_standard
J 2
(-1600 2300);
DISPLAY 0.787234 (-1600 2300);
PAINT MONO (-1600 2300);
DISPLAY INVISIBLE (-1600 2300);
FORCEADD TAP..6
R 2
(-1600 2250);
FORCEPROP 3 LASTPIN (-1650 2250) SIG_NAME M_A_DQ<21>
J 0
(-1640 2260);
DISPLAY 0.659574 (-1640 2260);
PAINT MONO (-1640 2260);
DISPLAY INVISIBLE (-1640 2260);
FORCEPROP 1 LASTPIN (-1650 2250) BN 21
J 2
(-1600 2260);
DISPLAY 0.617021 (-1600 2260);
PAINT PINK (-1600 2260);
FORCEPROP 1 LAST PATH I168
J 2
(-1600 2250);
DISPLAY 0.936170 (-1600 2250);
PAINT GREEN (-1600 2250);
DISPLAY INVISIBLE (-1600 2250);
FORCEPROP 1 LAST HDL_TAP TRUE
J 2
(-1925 2125);
DISPLAY 1.234043 (-1925 2125);
PAINT GREEN (-1925 2125);
DISPLAY INVISIBLE (-1925 2125);
FORCEPROP 1 LAST BODY_TYPE PLUMBING
J 2
(-1600 2200);
DISPLAY 1.234043 (-1600 2200);
PAINT GREEN (-1600 2200);
DISPLAY INVISIBLE (-1600 2200);
FORCEPROP 2 LAST CDS_LIB mstr_standard
J 2
(-1600 2250);
DISPLAY 0.787234 (-1600 2250);
PAINT MONO (-1600 2250);
DISPLAY INVISIBLE (-1600 2250);
FORCEADD TAP..6
R 2
(-1600 2350);
FORCEPROP 3 LASTPIN (-1650 2350) SIG_NAME M_A_DQ<23>
J 0
(-1640 2360);
DISPLAY 0.659574 (-1640 2360);
PAINT MONO (-1640 2360);
DISPLAY INVISIBLE (-1640 2360);
FORCEPROP 1 LASTPIN (-1650 2350) BN 23
J 2
(-1600 2360);
DISPLAY 0.617021 (-1600 2360);
PAINT PINK (-1600 2360);
FORCEPROP 1 LAST PATH I169
J 2
(-1600 2350);
DISPLAY 0.936170 (-1600 2350);
PAINT GREEN (-1600 2350);
DISPLAY INVISIBLE (-1600 2350);
FORCEPROP 1 LAST HDL_TAP TRUE
J 2
(-1925 2225);
DISPLAY 1.234043 (-1925 2225);
PAINT GREEN (-1925 2225);
DISPLAY INVISIBLE (-1925 2225);
FORCEPROP 1 LAST BODY_TYPE PLUMBING
J 2
(-1600 2300);
DISPLAY 1.234043 (-1600 2300);
PAINT GREEN (-1600 2300);
DISPLAY INVISIBLE (-1600 2300);
FORCEPROP 2 LAST CDS_LIB mstr_standard
J 2
(-1600 2350);
DISPLAY 0.787234 (-1600 2350);
PAINT MONO (-1600 2350);
DISPLAY INVISIBLE (-1600 2350);
FORCEADD TAP..6
R 2
(-1600 2400);
FORCEPROP 3 LASTPIN (-1650 2400) SIG_NAME M_A_DQ<22>
J 0
(-1640 2410);
DISPLAY 0.659574 (-1640 2410);
PAINT MONO (-1640 2410);
DISPLAY INVISIBLE (-1640 2410);
FORCEPROP 1 LASTPIN (-1650 2400) BN 22
J 2
(-1600 2410);
DISPLAY 0.617021 (-1600 2410);
PAINT PINK (-1600 2410);
FORCEPROP 1 LAST PATH I170
J 2
(-1600 2400);
DISPLAY 0.936170 (-1600 2400);
PAINT GREEN (-1600 2400);
DISPLAY INVISIBLE (-1600 2400);
FORCEPROP 1 LAST HDL_TAP TRUE
J 2
(-1925 2275);
DISPLAY 1.234043 (-1925 2275);
PAINT GREEN (-1925 2275);
DISPLAY INVISIBLE (-1925 2275);
FORCEPROP 1 LAST BODY_TYPE PLUMBING
J 2
(-1600 2350);
DISPLAY 1.234043 (-1600 2350);
PAINT GREEN (-1600 2350);
DISPLAY INVISIBLE (-1600 2350);
FORCEPROP 2 LAST CDS_LIB mstr_standard
J 2
(-1600 2400);
DISPLAY 0.787234 (-1600 2400);
PAINT MONO (-1600 2400);
DISPLAY INVISIBLE (-1600 2400);
FORCEADD TAP..6
R 2
(-1600 2500);
FORCEPROP 3 LASTPIN (-1650 2500) SIG_NAME M_A_DQ<24>
J 0
(-1640 2510);
DISPLAY 0.659574 (-1640 2510);
PAINT MONO (-1640 2510);
DISPLAY INVISIBLE (-1640 2510);
FORCEPROP 1 LASTPIN (-1650 2500) BN 24
J 2
(-1600 2510);
DISPLAY 0.617021 (-1600 2510);
PAINT PINK (-1600 2510);
FORCEPROP 1 LAST PATH I171
J 2
(-1600 2500);
DISPLAY 0.936170 (-1600 2500);
PAINT GREEN (-1600 2500);
DISPLAY INVISIBLE (-1600 2500);
FORCEPROP 1 LAST HDL_TAP TRUE
J 2
(-1925 2375);
DISPLAY 1.234043 (-1925 2375);
PAINT GREEN (-1925 2375);
DISPLAY INVISIBLE (-1925 2375);
FORCEPROP 1 LAST BODY_TYPE PLUMBING
J 2
(-1600 2450);
DISPLAY 1.234043 (-1600 2450);
PAINT GREEN (-1600 2450);
DISPLAY INVISIBLE (-1600 2450);
FORCEPROP 2 LAST CDS_LIB mstr_standard
J 2
(-1600 2500);
DISPLAY 0.787234 (-1600 2500);
PAINT MONO (-1600 2500);
DISPLAY INVISIBLE (-1600 2500);
FORCEADD TAP..6
R 2
(-1600 2450);
FORCEPROP 3 LASTPIN (-1650 2450) SIG_NAME M_A_DQ<25>
J 0
(-1640 2460);
DISPLAY 0.659574 (-1640 2460);
PAINT MONO (-1640 2460);
DISPLAY INVISIBLE (-1640 2460);
FORCEPROP 1 LASTPIN (-1650 2450) BN 25
J 2
(-1600 2460);
DISPLAY 0.617021 (-1600 2460);
PAINT PINK (-1600 2460);
FORCEPROP 1 LAST PATH I172
J 2
(-1600 2450);
DISPLAY 0.936170 (-1600 2450);
PAINT GREEN (-1600 2450);
DISPLAY INVISIBLE (-1600 2450);
FORCEPROP 1 LAST HDL_TAP TRUE
J 2
(-1925 2325);
DISPLAY 1.234043 (-1925 2325);
PAINT GREEN (-1925 2325);
DISPLAY INVISIBLE (-1925 2325);
FORCEPROP 1 LAST BODY_TYPE PLUMBING
J 2
(-1600 2400);
DISPLAY 1.234043 (-1600 2400);
PAINT GREEN (-1600 2400);
DISPLAY INVISIBLE (-1600 2400);
FORCEPROP 2 LAST CDS_LIB mstr_standard
J 2
(-1600 2450);
DISPLAY 0.787234 (-1600 2450);
PAINT MONO (-1600 2450);
DISPLAY INVISIBLE (-1600 2450);
FORCEADD TAP..6
R 2
(-1600 2550);
FORCEPROP 3 LASTPIN (-1650 2550) SIG_NAME M_A_DQ<27>
J 0
(-1640 2560);
DISPLAY 0.659574 (-1640 2560);
PAINT MONO (-1640 2560);
DISPLAY INVISIBLE (-1640 2560);
FORCEPROP 1 LASTPIN (-1650 2550) BN 27
J 2
(-1600 2560);
DISPLAY 0.617021 (-1600 2560);
PAINT PINK (-1600 2560);
FORCEPROP 1 LAST PATH I173
J 2
(-1600 2550);
DISPLAY 0.936170 (-1600 2550);
PAINT GREEN (-1600 2550);
DISPLAY INVISIBLE (-1600 2550);
FORCEPROP 1 LAST HDL_TAP TRUE
J 2
(-1925 2425);
DISPLAY 1.234043 (-1925 2425);
PAINT GREEN (-1925 2425);
DISPLAY INVISIBLE (-1925 2425);
FORCEPROP 1 LAST BODY_TYPE PLUMBING
J 2
(-1600 2500);
DISPLAY 1.234043 (-1600 2500);
PAINT GREEN (-1600 2500);
DISPLAY INVISIBLE (-1600 2500);
FORCEPROP 2 LAST CDS_LIB mstr_standard
J 2
(-1600 2550);
DISPLAY 0.787234 (-1600 2550);
PAINT MONO (-1600 2550);
DISPLAY INVISIBLE (-1600 2550);
FORCEADD TAP..6
R 2
(-1600 2600);
FORCEPROP 3 LASTPIN (-1650 2600) SIG_NAME M_A_DQ<26>
J 0
(-1640 2610);
DISPLAY 0.659574 (-1640 2610);
PAINT MONO (-1640 2610);
DISPLAY INVISIBLE (-1640 2610);
FORCEPROP 1 LASTPIN (-1650 2600) BN 26
J 2
(-1600 2610);
DISPLAY 0.617021 (-1600 2610);
PAINT PINK (-1600 2610);
FORCEPROP 1 LAST PATH I174
J 2
(-1600 2600);
DISPLAY 0.936170 (-1600 2600);
PAINT GREEN (-1600 2600);
DISPLAY INVISIBLE (-1600 2600);
FORCEPROP 1 LAST HDL_TAP TRUE
J 2
(-1925 2475);
DISPLAY 1.234043 (-1925 2475);
PAINT GREEN (-1925 2475);
DISPLAY INVISIBLE (-1925 2475);
FORCEPROP 1 LAST BODY_TYPE PLUMBING
J 2
(-1600 2550);
DISPLAY 1.234043 (-1600 2550);
PAINT GREEN (-1600 2550);
DISPLAY INVISIBLE (-1600 2550);
FORCEPROP 2 LAST CDS_LIB mstr_standard
J 2
(-1600 2600);
DISPLAY 0.787234 (-1600 2600);
PAINT MONO (-1600 2600);
DISPLAY INVISIBLE (-1600 2600);
FORCEADD TAP..6
R 2
(-1600 2650);
FORCEPROP 3 LASTPIN (-1650 2650) SIG_NAME M_A_DQ<29>
J 0
(-1640 2660);
DISPLAY 0.659574 (-1640 2660);
PAINT MONO (-1640 2660);
DISPLAY INVISIBLE (-1640 2660);
FORCEPROP 1 LASTPIN (-1650 2650) BN 29
J 2
(-1600 2660);
DISPLAY 0.617021 (-1600 2660);
PAINT PINK (-1600 2660);
FORCEPROP 1 LAST PATH I175
J 2
(-1600 2650);
DISPLAY 0.936170 (-1600 2650);
PAINT GREEN (-1600 2650);
DISPLAY INVISIBLE (-1600 2650);
FORCEPROP 1 LAST HDL_TAP TRUE
J 2
(-1925 2525);
DISPLAY 1.234043 (-1925 2525);
PAINT GREEN (-1925 2525);
DISPLAY INVISIBLE (-1925 2525);
FORCEPROP 1 LAST BODY_TYPE PLUMBING
J 2
(-1600 2600);
DISPLAY 1.234043 (-1600 2600);
PAINT GREEN (-1600 2600);
DISPLAY INVISIBLE (-1600 2600);
FORCEPROP 2 LAST CDS_LIB mstr_standard
J 2
(-1600 2650);
DISPLAY 0.787234 (-1600 2650);
PAINT MONO (-1600 2650);
DISPLAY INVISIBLE (-1600 2650);
FORCEADD TAP..6
R 2
(-1600 1700);
FORCEPROP 3 LASTPIN (-1650 1700) SIG_NAME M_A_DQ<8>
J 0
(-1640 1710);
DISPLAY 0.659574 (-1640 1710);
PAINT MONO (-1640 1710);
DISPLAY INVISIBLE (-1640 1710);
FORCEPROP 1 LASTPIN (-1650 1700) BN 8
J 2
(-1600 1710);
DISPLAY 0.617021 (-1600 1710);
PAINT PINK (-1600 1710);
FORCEPROP 1 LAST PATH I176
J 2
(-1600 1700);
DISPLAY 0.936170 (-1600 1700);
PAINT GREEN (-1600 1700);
DISPLAY INVISIBLE (-1600 1700);
FORCEPROP 1 LAST HDL_TAP TRUE
J 2
(-1925 1575);
DISPLAY 1.234043 (-1925 1575);
PAINT GREEN (-1925 1575);
DISPLAY INVISIBLE (-1925 1575);
FORCEPROP 1 LAST BODY_TYPE PLUMBING
J 2
(-1600 1650);
DISPLAY 1.234043 (-1600 1650);
PAINT GREEN (-1600 1650);
DISPLAY INVISIBLE (-1600 1650);
FORCEPROP 2 LAST CDS_LIB mstr_standard
J 2
(-1600 1700);
DISPLAY 0.787234 (-1600 1700);
PAINT MONO (-1600 1700);
DISPLAY INVISIBLE (-1600 1700);
FORCEADD TAP..6
R 2
(-1600 1750);
FORCEPROP 3 LASTPIN (-1650 1750) SIG_NAME M_A_DQ<11>
J 0
(-1640 1760);
DISPLAY 0.659574 (-1640 1760);
PAINT MONO (-1640 1760);
DISPLAY INVISIBLE (-1640 1760);
FORCEPROP 1 LASTPIN (-1650 1750) BN 11
J 2
(-1600 1760);
DISPLAY 0.617021 (-1600 1760);
PAINT PINK (-1600 1760);
FORCEPROP 1 LAST PATH I177
J 2
(-1600 1750);
DISPLAY 0.936170 (-1600 1750);
PAINT GREEN (-1600 1750);
DISPLAY INVISIBLE (-1600 1750);
FORCEPROP 1 LAST HDL_TAP TRUE
J 2
(-1925 1625);
DISPLAY 1.234043 (-1925 1625);
PAINT GREEN (-1925 1625);
DISPLAY INVISIBLE (-1925 1625);
FORCEPROP 1 LAST BODY_TYPE PLUMBING
J 2
(-1600 1700);
DISPLAY 1.234043 (-1600 1700);
PAINT GREEN (-1600 1700);
DISPLAY INVISIBLE (-1600 1700);
FORCEPROP 2 LAST CDS_LIB mstr_standard
J 2
(-1600 1750);
DISPLAY 0.787234 (-1600 1750);
PAINT MONO (-1600 1750);
DISPLAY INVISIBLE (-1600 1750);
FORCEADD TAP..6
R 2
(-1600 1850);
FORCEPROP 3 LASTPIN (-1650 1850) SIG_NAME M_A_DQ<13>
J 0
(-1640 1860);
DISPLAY 0.659574 (-1640 1860);
PAINT MONO (-1640 1860);
DISPLAY INVISIBLE (-1640 1860);
FORCEPROP 1 LASTPIN (-1650 1850) BN 13
J 2
(-1600 1860);
DISPLAY 0.617021 (-1600 1860);
PAINT PINK (-1600 1860);
FORCEPROP 1 LAST PATH I178
J 2
(-1600 1850);
DISPLAY 0.936170 (-1600 1850);
PAINT GREEN (-1600 1850);
DISPLAY INVISIBLE (-1600 1850);
FORCEPROP 1 LAST HDL_TAP TRUE
J 2
(-1925 1725);
DISPLAY 1.234043 (-1925 1725);
PAINT GREEN (-1925 1725);
DISPLAY INVISIBLE (-1925 1725);
FORCEPROP 1 LAST BODY_TYPE PLUMBING
J 2
(-1600 1800);
DISPLAY 1.234043 (-1600 1800);
PAINT GREEN (-1600 1800);
DISPLAY INVISIBLE (-1600 1800);
FORCEPROP 2 LAST CDS_LIB mstr_standard
J 2
(-1600 1850);
DISPLAY 0.787234 (-1600 1850);
PAINT MONO (-1600 1850);
DISPLAY INVISIBLE (-1600 1850);
FORCEADD TAP..6
R 2
(-1600 1800);
FORCEPROP 3 LASTPIN (-1650 1800) SIG_NAME M_A_DQ<10>
J 0
(-1640 1810);
DISPLAY 0.659574 (-1640 1810);
PAINT MONO (-1640 1810);
DISPLAY INVISIBLE (-1640 1810);
FORCEPROP 1 LASTPIN (-1650 1800) BN 10
J 2
(-1600 1810);
DISPLAY 0.617021 (-1600 1810);
PAINT PINK (-1600 1810);
FORCEPROP 1 LAST PATH I179
J 2
(-1600 1800);
DISPLAY 0.936170 (-1600 1800);
PAINT GREEN (-1600 1800);
DISPLAY INVISIBLE (-1600 1800);
FORCEPROP 1 LAST HDL_TAP TRUE
J 2
(-1925 1675);
DISPLAY 1.234043 (-1925 1675);
PAINT GREEN (-1925 1675);
DISPLAY INVISIBLE (-1925 1675);
FORCEPROP 1 LAST BODY_TYPE PLUMBING
J 2
(-1600 1750);
DISPLAY 1.234043 (-1600 1750);
PAINT GREEN (-1600 1750);
DISPLAY INVISIBLE (-1600 1750);
FORCEPROP 2 LAST CDS_LIB mstr_standard
J 2
(-1600 1800);
DISPLAY 0.787234 (-1600 1800);
PAINT MONO (-1600 1800);
DISPLAY INVISIBLE (-1600 1800);
FORCEADD TAP..6
R 2
(-1600 1900);
FORCEPROP 3 LASTPIN (-1650 1900) SIG_NAME M_A_DQ<12>
J 0
(-1640 1910);
DISPLAY 0.659574 (-1640 1910);
PAINT MONO (-1640 1910);
DISPLAY INVISIBLE (-1640 1910);
FORCEPROP 1 LASTPIN (-1650 1900) BN 12
J 2
(-1600 1910);
DISPLAY 0.617021 (-1600 1910);
PAINT PINK (-1600 1910);
FORCEPROP 1 LAST PATH I180
J 2
(-1600 1900);
DISPLAY 0.936170 (-1600 1900);
PAINT GREEN (-1600 1900);
DISPLAY INVISIBLE (-1600 1900);
FORCEPROP 1 LAST HDL_TAP TRUE
J 2
(-1925 1775);
DISPLAY 1.234043 (-1925 1775);
PAINT GREEN (-1925 1775);
DISPLAY INVISIBLE (-1925 1775);
FORCEPROP 1 LAST BODY_TYPE PLUMBING
J 2
(-1600 1850);
DISPLAY 1.234043 (-1600 1850);
PAINT GREEN (-1600 1850);
DISPLAY INVISIBLE (-1600 1850);
FORCEPROP 2 LAST CDS_LIB mstr_standard
J 2
(-1600 1900);
DISPLAY 0.787234 (-1600 1900);
PAINT MONO (-1600 1900);
DISPLAY INVISIBLE (-1600 1900);
FORCEADD TAP..6
R 2
(-1600 1950);
FORCEPROP 3 LASTPIN (-1650 1950) SIG_NAME M_A_DQ<15>
J 0
(-1640 1960);
DISPLAY 0.659574 (-1640 1960);
PAINT MONO (-1640 1960);
DISPLAY INVISIBLE (-1640 1960);
FORCEPROP 1 LASTPIN (-1650 1950) BN 15
J 2
(-1600 1960);
DISPLAY 0.617021 (-1600 1960);
PAINT PINK (-1600 1960);
FORCEPROP 1 LAST PATH I181
J 2
(-1600 1950);
DISPLAY 0.936170 (-1600 1950);
PAINT GREEN (-1600 1950);
DISPLAY INVISIBLE (-1600 1950);
FORCEPROP 1 LAST HDL_TAP TRUE
J 2
(-1925 1825);
DISPLAY 1.234043 (-1925 1825);
PAINT GREEN (-1925 1825);
DISPLAY INVISIBLE (-1925 1825);
FORCEPROP 1 LAST BODY_TYPE PLUMBING
J 2
(-1600 1900);
DISPLAY 1.234043 (-1600 1900);
PAINT GREEN (-1600 1900);
DISPLAY INVISIBLE (-1600 1900);
FORCEPROP 2 LAST CDS_LIB mstr_standard
J 2
(-1600 1950);
DISPLAY 0.787234 (-1600 1950);
PAINT MONO (-1600 1950);
DISPLAY INVISIBLE (-1600 1950);
FORCEADD TAP..6
R 2
(-1600 1650);
FORCEPROP 3 LASTPIN (-1650 1650) SIG_NAME M_A_DQ<9>
J 0
(-1640 1660);
DISPLAY 0.659574 (-1640 1660);
PAINT MONO (-1640 1660);
DISPLAY INVISIBLE (-1640 1660);
FORCEPROP 1 LASTPIN (-1650 1650) BN 9
J 2
(-1600 1660);
DISPLAY 0.617021 (-1600 1660);
PAINT PINK (-1600 1660);
FORCEPROP 1 LAST PATH I182
J 2
(-1600 1650);
DISPLAY 0.936170 (-1600 1650);
PAINT GREEN (-1600 1650);
DISPLAY INVISIBLE (-1600 1650);
FORCEPROP 1 LAST HDL_TAP TRUE
J 2
(-1925 1525);
DISPLAY 1.234043 (-1925 1525);
PAINT GREEN (-1925 1525);
DISPLAY INVISIBLE (-1925 1525);
FORCEPROP 1 LAST BODY_TYPE PLUMBING
J 2
(-1600 1600);
DISPLAY 1.234043 (-1600 1600);
PAINT GREEN (-1600 1600);
DISPLAY INVISIBLE (-1600 1600);
FORCEPROP 2 LAST CDS_LIB mstr_standard
J 2
(-1600 1650);
DISPLAY 0.787234 (-1600 1650);
PAINT MONO (-1600 1650);
DISPLAY INVISIBLE (-1600 1650);
FORCEADD TAP..6
R 2
(-1600 1250);
FORCEPROP 3 LASTPIN (-1650 1250) SIG_NAME M_A_DQ<1>
J 0
(-1640 1260);
DISPLAY 0.659574 (-1640 1260);
PAINT MONO (-1640 1260);
DISPLAY INVISIBLE (-1640 1260);
FORCEPROP 1 LASTPIN (-1650 1250) BN 1
J 2
(-1600 1260);
DISPLAY 0.617021 (-1600 1260);
PAINT PINK (-1600 1260);
FORCEPROP 1 LAST PATH I183
J 2
(-1600 1250);
DISPLAY 0.936170 (-1600 1250);
PAINT GREEN (-1600 1250);
DISPLAY INVISIBLE (-1600 1250);
FORCEPROP 1 LAST HDL_TAP TRUE
J 2
(-1925 1125);
DISPLAY 1.234043 (-1925 1125);
PAINT GREEN (-1925 1125);
DISPLAY INVISIBLE (-1925 1125);
FORCEPROP 1 LAST BODY_TYPE PLUMBING
J 2
(-1600 1200);
DISPLAY 1.234043 (-1600 1200);
PAINT GREEN (-1600 1200);
DISPLAY INVISIBLE (-1600 1200);
FORCEPROP 2 LAST CDS_LIB mstr_standard
J 2
(-1600 1250);
DISPLAY 0.787234 (-1600 1250);
PAINT MONO (-1600 1250);
DISPLAY INVISIBLE (-1600 1250);
FORCEADD TAP..6
R 2
(-1600 1350);
FORCEPROP 3 LASTPIN (-1650 1350) SIG_NAME M_A_DQ<3>
J 0
(-1640 1360);
DISPLAY 0.659574 (-1640 1360);
PAINT MONO (-1640 1360);
DISPLAY INVISIBLE (-1640 1360);
FORCEPROP 1 LASTPIN (-1650 1350) BN 3
J 2
(-1600 1360);
DISPLAY 0.617021 (-1600 1360);
PAINT PINK (-1600 1360);
FORCEPROP 1 LAST PATH I184
J 2
(-1600 1350);
DISPLAY 0.936170 (-1600 1350);
PAINT GREEN (-1600 1350);
DISPLAY INVISIBLE (-1600 1350);
FORCEPROP 1 LAST HDL_TAP TRUE
J 2
(-1925 1225);
DISPLAY 1.234043 (-1925 1225);
PAINT GREEN (-1925 1225);
DISPLAY INVISIBLE (-1925 1225);
FORCEPROP 1 LAST BODY_TYPE PLUMBING
J 2
(-1600 1300);
DISPLAY 1.234043 (-1600 1300);
PAINT GREEN (-1600 1300);
DISPLAY INVISIBLE (-1600 1300);
FORCEPROP 2 LAST CDS_LIB mstr_standard
J 2
(-1600 1350);
DISPLAY 0.787234 (-1600 1350);
PAINT MONO (-1600 1350);
DISPLAY INVISIBLE (-1600 1350);
FORCEADD TAP..6
R 2
(-1600 1300);
FORCEPROP 3 LASTPIN (-1650 1300) SIG_NAME M_A_DQ<0>
J 0
(-1640 1310);
DISPLAY 0.659574 (-1640 1310);
PAINT MONO (-1640 1310);
DISPLAY INVISIBLE (-1640 1310);
FORCEPROP 1 LASTPIN (-1650 1300) BN 0
J 2
(-1600 1310);
DISPLAY 0.617021 (-1600 1310);
PAINT PINK (-1600 1310);
FORCEPROP 1 LAST PATH I185
J 2
(-1600 1300);
DISPLAY 0.936170 (-1600 1300);
PAINT GREEN (-1600 1300);
DISPLAY INVISIBLE (-1600 1300);
FORCEPROP 1 LAST HDL_TAP TRUE
J 2
(-1925 1175);
DISPLAY 1.234043 (-1925 1175);
PAINT GREEN (-1925 1175);
DISPLAY INVISIBLE (-1925 1175);
FORCEPROP 1 LAST BODY_TYPE PLUMBING
J 2
(-1600 1250);
DISPLAY 1.234043 (-1600 1250);
PAINT GREEN (-1600 1250);
DISPLAY INVISIBLE (-1600 1250);
FORCEPROP 2 LAST CDS_LIB mstr_standard
J 2
(-1600 1300);
DISPLAY 0.787234 (-1600 1300);
PAINT MONO (-1600 1300);
DISPLAY INVISIBLE (-1600 1300);
FORCEADD TAP..6
R 2
(-1600 1400);
FORCEPROP 3 LASTPIN (-1650 1400) SIG_NAME M_A_DQ<2>
J 0
(-1640 1410);
DISPLAY 0.659574 (-1640 1410);
PAINT MONO (-1640 1410);
DISPLAY INVISIBLE (-1640 1410);
FORCEPROP 1 LASTPIN (-1650 1400) BN 2
J 2
(-1600 1410);
DISPLAY 0.617021 (-1600 1410);
PAINT PINK (-1600 1410);
FORCEPROP 1 LAST PATH I186
J 2
(-1600 1400);
DISPLAY 0.936170 (-1600 1400);
PAINT GREEN (-1600 1400);
DISPLAY INVISIBLE (-1600 1400);
FORCEPROP 1 LAST HDL_TAP TRUE
J 2
(-1925 1275);
DISPLAY 1.234043 (-1925 1275);
PAINT GREEN (-1925 1275);
DISPLAY INVISIBLE (-1925 1275);
FORCEPROP 1 LAST BODY_TYPE PLUMBING
J 2
(-1600 1350);
DISPLAY 1.234043 (-1600 1350);
PAINT GREEN (-1600 1350);
DISPLAY INVISIBLE (-1600 1350);
FORCEPROP 2 LAST CDS_LIB mstr_standard
J 2
(-1600 1400);
DISPLAY 0.787234 (-1600 1400);
PAINT MONO (-1600 1400);
DISPLAY INVISIBLE (-1600 1400);
FORCEADD TAP..6
R 2
(-1600 1450);
FORCEPROP 3 LASTPIN (-1650 1450) SIG_NAME M_A_DQ<5>
J 0
(-1640 1460);
DISPLAY 0.659574 (-1640 1460);
PAINT MONO (-1640 1460);
DISPLAY INVISIBLE (-1640 1460);
FORCEPROP 1 LASTPIN (-1650 1450) BN 5
J 2
(-1600 1460);
DISPLAY 0.617021 (-1600 1460);
PAINT PINK (-1600 1460);
FORCEPROP 1 LAST PATH I187
J 2
(-1600 1450);
DISPLAY 0.936170 (-1600 1450);
PAINT GREEN (-1600 1450);
DISPLAY INVISIBLE (-1600 1450);
FORCEPROP 1 LAST HDL_TAP TRUE
J 2
(-1925 1325);
DISPLAY 1.234043 (-1925 1325);
PAINT GREEN (-1925 1325);
DISPLAY INVISIBLE (-1925 1325);
FORCEPROP 1 LAST BODY_TYPE PLUMBING
J 2
(-1600 1400);
DISPLAY 1.234043 (-1600 1400);
PAINT GREEN (-1600 1400);
DISPLAY INVISIBLE (-1600 1400);
FORCEPROP 2 LAST CDS_LIB mstr_standard
J 2
(-1600 1450);
DISPLAY 0.787234 (-1600 1450);
PAINT MONO (-1600 1450);
DISPLAY INVISIBLE (-1600 1450);
FORCEADD TAP..6
R 2
(-1600 1500);
FORCEPROP 3 LASTPIN (-1650 1500) SIG_NAME M_A_DQ<4>
J 0
(-1640 1510);
DISPLAY 0.659574 (-1640 1510);
PAINT MONO (-1640 1510);
DISPLAY INVISIBLE (-1640 1510);
FORCEPROP 1 LASTPIN (-1650 1500) BN 4
J 2
(-1600 1510);
DISPLAY 0.617021 (-1600 1510);
PAINT PINK (-1600 1510);
FORCEPROP 1 LAST PATH I188
J 2
(-1600 1500);
DISPLAY 0.936170 (-1600 1500);
PAINT GREEN (-1600 1500);
DISPLAY INVISIBLE (-1600 1500);
FORCEPROP 1 LAST HDL_TAP TRUE
J 2
(-1925 1375);
DISPLAY 1.234043 (-1925 1375);
PAINT GREEN (-1925 1375);
DISPLAY INVISIBLE (-1925 1375);
FORCEPROP 1 LAST BODY_TYPE PLUMBING
J 2
(-1600 1450);
DISPLAY 1.234043 (-1600 1450);
PAINT GREEN (-1600 1450);
DISPLAY INVISIBLE (-1600 1450);
FORCEPROP 2 LAST CDS_LIB mstr_standard
J 2
(-1600 1500);
DISPLAY 0.787234 (-1600 1500);
PAINT MONO (-1600 1500);
DISPLAY INVISIBLE (-1600 1500);
FORCEADD TAP..6
R 2
(-1600 1600);
FORCEPROP 3 LASTPIN (-1650 1600) SIG_NAME M_A_DQ<6>
J 0
(-1640 1610);
DISPLAY 0.659574 (-1640 1610);
PAINT MONO (-1640 1610);
DISPLAY INVISIBLE (-1640 1610);
FORCEPROP 1 LASTPIN (-1650 1600) BN 6
J 2
(-1600 1610);
DISPLAY 0.617021 (-1600 1610);
PAINT PINK (-1600 1610);
FORCEPROP 1 LAST PATH I189
J 2
(-1600 1600);
DISPLAY 0.936170 (-1600 1600);
PAINT GREEN (-1600 1600);
DISPLAY INVISIBLE (-1600 1600);
FORCEPROP 1 LAST HDL_TAP TRUE
J 2
(-1925 1475);
DISPLAY 1.234043 (-1925 1475);
PAINT GREEN (-1925 1475);
DISPLAY INVISIBLE (-1925 1475);
FORCEPROP 1 LAST BODY_TYPE PLUMBING
J 2
(-1600 1550);
DISPLAY 1.234043 (-1600 1550);
PAINT GREEN (-1600 1550);
DISPLAY INVISIBLE (-1600 1550);
FORCEPROP 2 LAST CDS_LIB mstr_standard
J 2
(-1600 1600);
DISPLAY 0.787234 (-1600 1600);
PAINT MONO (-1600 1600);
DISPLAY INVISIBLE (-1600 1600);
FORCEADD TAP..6
R 2
(-1600 1550);
FORCEPROP 3 LASTPIN (-1650 1550) SIG_NAME M_A_DQ<7>
J 0
(-1640 1560);
DISPLAY 0.659574 (-1640 1560);
PAINT MONO (-1640 1560);
DISPLAY INVISIBLE (-1640 1560);
FORCEPROP 1 LASTPIN (-1650 1550) BN 7
J 2
(-1600 1560);
DISPLAY 0.617021 (-1600 1560);
PAINT PINK (-1600 1560);
FORCEPROP 1 LAST PATH I190
J 2
(-1600 1550);
DISPLAY 0.936170 (-1600 1550);
PAINT GREEN (-1600 1550);
DISPLAY INVISIBLE (-1600 1550);
FORCEPROP 1 LAST HDL_TAP TRUE
J 2
(-1925 1425);
DISPLAY 1.234043 (-1925 1425);
PAINT GREEN (-1925 1425);
DISPLAY INVISIBLE (-1925 1425);
FORCEPROP 1 LAST BODY_TYPE PLUMBING
J 2
(-1600 1500);
DISPLAY 1.234043 (-1600 1500);
PAINT GREEN (-1600 1500);
DISPLAY INVISIBLE (-1600 1500);
FORCEPROP 2 LAST CDS_LIB mstr_standard
J 2
(-1600 1550);
DISPLAY 0.787234 (-1600 1550);
PAINT MONO (-1600 1550);
DISPLAY INVISIBLE (-1600 1550);
FORCEADD OFFPAGE..3
(-1000 4450);
FORCEPROP 2 LAST $XR1 44 
J 0
(-696 4450);
DISPLAY 0.638298 (-696 4450);
PAINT MONO (-696 4450);
FORCEPROP 2 LAST $XR0 23 
J 0
(-786 4450);
DISPLAY 0.638298 (-786 4450);
PAINT MONO (-786 4450);
FORCEPROP 2 LAST PATH I191
J 0
(-950 4525);
DISPLAY 0.787234 (-950 4525);
PAINT MONO (-950 4525);
DISPLAY INVISIBLE (-950 4525);
FORCEPROP 1 LAST COMMENT_BODY TRUE
J 0
(-1050 4350);
DISPLAY 0.936170 (-1050 4350);
PAINT GREEN (-1050 4350);
DISPLAY INVISIBLE (-1050 4350);
FORCEPROP 1 LAST OFFPAGE TRUE
J 0
(-675 4325);
DISPLAY 0.936170 (-675 4325);
PAINT GREEN (-675 4325);
DISPLAY INVISIBLE (-675 4325);
FORCEPROP 2 LAST CDS_LIB mstr_standard
J 0
(-1000 4450);
DISPLAY 0.787234 (-1000 4450);
PAINT MONO (-1000 4450);
DISPLAY INVISIBLE (-1000 4450);
FORCEADD TAP..6
R 2
(650 4200);
FORCEPROP 3 LASTPIN (600 4200) SIG_NAME M_A_DQS_DP<10>
J 0
(610 4210);
DISPLAY 0.659574 (610 4210);
PAINT MONO (610 4210);
DISPLAY INVISIBLE (610 4210);
FORCEPROP 1 LASTPIN (600 4200) BN 10
J 2
(650 4210);
DISPLAY 0.617021 (650 4210);
PAINT PINK (650 4210);
FORCEPROP 1 LAST PATH I192
J 2
(650 4200);
DISPLAY 0.936170 (650 4200);
PAINT GREEN (650 4200);
DISPLAY INVISIBLE (650 4200);
FORCEPROP 1 LAST HDL_TAP TRUE
J 2
(325 4075);
DISPLAY 1.234043 (325 4075);
PAINT GREEN (325 4075);
DISPLAY INVISIBLE (325 4075);
FORCEPROP 1 LAST BODY_TYPE PLUMBING
J 2
(650 4150);
DISPLAY 1.234043 (650 4150);
PAINT GREEN (650 4150);
DISPLAY INVISIBLE (650 4150);
FORCEPROP 2 LAST CDS_LIB mstr_standard
J 0
(650 4200);
DISPLAY 0.787234 (650 4200);
PAINT MONO (650 4200);
DISPLAY INVISIBLE (650 4200);
FORCEADD TAP..6
R 2
(650 4300);
FORCEPROP 3 LASTPIN (600 4300) SIG_NAME M_A_DQS_DP<11>
J 0
(610 4310);
DISPLAY 0.659574 (610 4310);
PAINT MONO (610 4310);
DISPLAY INVISIBLE (610 4310);
FORCEPROP 1 LASTPIN (600 4300) BN 11
J 2
(650 4310);
DISPLAY 0.617021 (650 4310);
PAINT PINK (650 4310);
FORCEPROP 1 LAST PATH I193
J 2
(650 4300);
DISPLAY 0.936170 (650 4300);
PAINT GREEN (650 4300);
DISPLAY INVISIBLE (650 4300);
FORCEPROP 1 LAST HDL_TAP TRUE
J 2
(325 4175);
DISPLAY 1.234043 (325 4175);
PAINT GREEN (325 4175);
DISPLAY INVISIBLE (325 4175);
FORCEPROP 1 LAST BODY_TYPE PLUMBING
J 2
(650 4250);
DISPLAY 1.234043 (650 4250);
PAINT GREEN (650 4250);
DISPLAY INVISIBLE (650 4250);
FORCEPROP 2 LAST CDS_LIB mstr_standard
J 0
(650 4300);
DISPLAY 0.787234 (650 4300);
PAINT MONO (650 4300);
DISPLAY INVISIBLE (650 4300);
FORCEADD TAP..6
R 2
(650 4000);
FORCEPROP 3 LASTPIN (600 4000) SIG_NAME M_A_DQS_DP<8>
J 0
(610 4010);
DISPLAY 0.659574 (610 4010);
PAINT MONO (610 4010);
DISPLAY INVISIBLE (610 4010);
FORCEPROP 1 LASTPIN (600 4000) BN 8
J 2
(650 4010);
DISPLAY 0.617021 (650 4010);
PAINT PINK (650 4010);
FORCEPROP 1 LAST PATH I194
J 2
(650 4000);
DISPLAY 0.936170 (650 4000);
PAINT GREEN (650 4000);
DISPLAY INVISIBLE (650 4000);
FORCEPROP 1 LAST HDL_TAP TRUE
J 2
(325 3875);
DISPLAY 1.234043 (325 3875);
PAINT GREEN (325 3875);
DISPLAY INVISIBLE (325 3875);
FORCEPROP 1 LAST BODY_TYPE PLUMBING
J 2
(650 3950);
DISPLAY 1.234043 (650 3950);
PAINT GREEN (650 3950);
DISPLAY INVISIBLE (650 3950);
FORCEPROP 2 LAST CDS_LIB mstr_standard
J 0
(650 4000);
DISPLAY 0.787234 (650 4000);
PAINT MONO (650 4000);
DISPLAY INVISIBLE (650 4000);
FORCEADD TAP..6
R 2
(650 4100);
FORCEPROP 3 LASTPIN (600 4100) SIG_NAME M_A_DQS_DP<9>
J 0
(610 4110);
DISPLAY 0.659574 (610 4110);
PAINT MONO (610 4110);
DISPLAY INVISIBLE (610 4110);
FORCEPROP 1 LASTPIN (600 4100) BN 9
J 2
(650 4110);
DISPLAY 0.617021 (650 4110);
PAINT PINK (650 4110);
FORCEPROP 1 LAST PATH I195
J 2
(650 4100);
DISPLAY 0.936170 (650 4100);
PAINT GREEN (650 4100);
DISPLAY INVISIBLE (650 4100);
FORCEPROP 1 LAST HDL_TAP TRUE
J 2
(325 3975);
DISPLAY 1.234043 (325 3975);
PAINT GREEN (325 3975);
DISPLAY INVISIBLE (325 3975);
FORCEPROP 1 LAST BODY_TYPE PLUMBING
J 2
(650 4050);
DISPLAY 1.234043 (650 4050);
PAINT GREEN (650 4050);
DISPLAY INVISIBLE (650 4050);
FORCEPROP 2 LAST CDS_LIB mstr_standard
J 0
(650 4100);
DISPLAY 0.787234 (650 4100);
PAINT MONO (650 4100);
DISPLAY INVISIBLE (650 4100);
FORCEADD TAP..6
R 2
(650 3700);
FORCEPROP 3 LASTPIN (600 3700) SIG_NAME M_A_DQS_DP<5>
J 0
(610 3710);
DISPLAY 0.659574 (610 3710);
PAINT MONO (610 3710);
DISPLAY INVISIBLE (610 3710);
FORCEPROP 1 LASTPIN (600 3700) BN 5
J 2
(650 3710);
DISPLAY 0.617021 (650 3710);
PAINT PINK (650 3710);
FORCEPROP 1 LAST PATH I196
J 2
(650 3700);
DISPLAY 0.936170 (650 3700);
PAINT GREEN (650 3700);
DISPLAY INVISIBLE (650 3700);
FORCEPROP 1 LAST HDL_TAP TRUE
J 2
(325 3575);
DISPLAY 1.234043 (325 3575);
PAINT GREEN (325 3575);
DISPLAY INVISIBLE (325 3575);
FORCEPROP 1 LAST BODY_TYPE PLUMBING
J 2
(650 3650);
DISPLAY 1.234043 (650 3650);
PAINT GREEN (650 3650);
DISPLAY INVISIBLE (650 3650);
FORCEPROP 2 LAST CDS_LIB mstr_standard
J 0
(650 3700);
DISPLAY 0.787234 (650 3700);
PAINT MONO (650 3700);
DISPLAY INVISIBLE (650 3700);
FORCEADD TAP..6
R 2
(650 3800);
FORCEPROP 3 LASTPIN (600 3800) SIG_NAME M_A_DQS_DP<6>
J 0
(610 3810);
DISPLAY 0.659574 (610 3810);
PAINT MONO (610 3810);
DISPLAY INVISIBLE (610 3810);
FORCEPROP 1 LASTPIN (600 3800) BN 6
J 2
(650 3810);
DISPLAY 0.617021 (650 3810);
PAINT PINK (650 3810);
FORCEPROP 1 LAST PATH I197
J 2
(650 3800);
DISPLAY 0.936170 (650 3800);
PAINT GREEN (650 3800);
DISPLAY INVISIBLE (650 3800);
FORCEPROP 1 LAST HDL_TAP TRUE
J 2
(325 3675);
DISPLAY 1.234043 (325 3675);
PAINT GREEN (325 3675);
DISPLAY INVISIBLE (325 3675);
FORCEPROP 1 LAST BODY_TYPE PLUMBING
J 2
(650 3750);
DISPLAY 1.234043 (650 3750);
PAINT GREEN (650 3750);
DISPLAY INVISIBLE (650 3750);
FORCEPROP 2 LAST CDS_LIB mstr_standard
J 0
(650 3800);
DISPLAY 0.787234 (650 3800);
PAINT MONO (650 3800);
DISPLAY INVISIBLE (650 3800);
FORCEADD TAP..6
R 2
(650 3900);
FORCEPROP 3 LASTPIN (600 3900) SIG_NAME M_A_DQS_DP<7>
J 0
(610 3910);
DISPLAY 0.659574 (610 3910);
PAINT MONO (610 3910);
DISPLAY INVISIBLE (610 3910);
FORCEPROP 1 LASTPIN (600 3900) BN 7
J 2
(650 3910);
DISPLAY 0.617021 (650 3910);
PAINT PINK (650 3910);
FORCEPROP 1 LAST PATH I198
J 2
(650 3900);
DISPLAY 0.936170 (650 3900);
PAINT GREEN (650 3900);
DISPLAY INVISIBLE (650 3900);
FORCEPROP 1 LAST HDL_TAP TRUE
J 2
(325 3775);
DISPLAY 1.234043 (325 3775);
PAINT GREEN (325 3775);
DISPLAY INVISIBLE (325 3775);
FORCEPROP 1 LAST BODY_TYPE PLUMBING
J 2
(650 3850);
DISPLAY 1.234043 (650 3850);
PAINT GREEN (650 3850);
DISPLAY INVISIBLE (650 3850);
FORCEPROP 2 LAST CDS_LIB mstr_standard
J 0
(650 3900);
DISPLAY 0.787234 (650 3900);
PAINT MONO (650 3900);
DISPLAY INVISIBLE (650 3900);
FORCEADD TAP..6
R 2
(650 3500);
FORCEPROP 3 LASTPIN (600 3500) SIG_NAME M_A_DQS_DP<3>
J 0
(610 3510);
DISPLAY 0.659574 (610 3510);
PAINT MONO (610 3510);
DISPLAY INVISIBLE (610 3510);
FORCEPROP 1 LASTPIN (600 3500) BN 3
J 2
(650 3510);
DISPLAY 0.617021 (650 3510);
PAINT PINK (650 3510);
FORCEPROP 1 LAST PATH I199
J 2
(650 3500);
DISPLAY 0.936170 (650 3500);
PAINT GREEN (650 3500);
DISPLAY INVISIBLE (650 3500);
FORCEPROP 1 LAST HDL_TAP TRUE
J 2
(325 3375);
DISPLAY 1.234043 (325 3375);
PAINT GREEN (325 3375);
DISPLAY INVISIBLE (325 3375);
FORCEPROP 1 LAST BODY_TYPE PLUMBING
J 2
(650 3450);
DISPLAY 1.234043 (650 3450);
PAINT GREEN (650 3450);
DISPLAY INVISIBLE (650 3450);
FORCEPROP 2 LAST CDS_LIB mstr_standard
J 0
(650 3500);
DISPLAY 0.787234 (650 3500);
PAINT MONO (650 3500);
DISPLAY INVISIBLE (650 3500);
FORCEADD SCONN288_H44441004..2
(-50 4050);
FORCEPROP 2 LASTPIN (400 4250) $PN 30
J 0
(410 4260);
DISPLAY 0.617021 (410 4260);
PAINT ORANGE (410 4260);
FORCEPROP 2 LASTPIN (400 3150) $PN 152
J 0
(410 3160);
DISPLAY 0.617021 (410 3160);
PAINT ORANGE (410 3160);
FORCEPROP 2 LASTPIN (400 3200) $PN 153
J 0
(410 3210);
DISPLAY 0.617021 (410 3210);
PAINT ORANGE (410 3210);
FORCEPROP 2 LASTPIN (400 3250) $PN 163
J 0
(410 3260);
DISPLAY 0.617021 (410 3260);
PAINT ORANGE (410 3260);
FORCEPROP 2 LASTPIN (400 3300) $PN 164
J 0
(410 3310);
DISPLAY 0.617021 (410 3310);
PAINT ORANGE (410 3310);
FORCEPROP 2 LASTPIN (400 3350) $PN 174
J 0
(410 3360);
DISPLAY 0.617021 (410 3360);
PAINT ORANGE (410 3360);
FORCEPROP 2 LASTPIN (400 3400) $PN 175
J 0
(410 3410);
DISPLAY 0.617021 (410 3410);
PAINT ORANGE (410 3410);
FORCEPROP 2 LASTPIN (400 3450) $PN 185
J 0
(410 3460);
DISPLAY 0.617021 (410 3460);
PAINT ORANGE (410 3460);
FORCEPROP 2 LASTPIN (400 3500) $PN 186
J 0
(410 3510);
DISPLAY 0.617021 (410 3510);
PAINT ORANGE (410 3510);
FORCEPROP 2 LASTPIN (400 3550) $PN 244
J 0
(410 3560);
DISPLAY 0.617021 (410 3560);
PAINT ORANGE (410 3560);
FORCEPROP 2 LASTPIN (400 3600) $PN 245
J 0
(410 3610);
DISPLAY 0.617021 (410 3610);
PAINT ORANGE (410 3610);
FORCEPROP 2 LASTPIN (400 3650) $PN 255
J 0
(410 3660);
DISPLAY 0.617021 (410 3660);
PAINT ORANGE (410 3660);
FORCEPROP 2 LASTPIN (400 3700) $PN 256
J 0
(410 3710);
DISPLAY 0.617021 (410 3710);
PAINT ORANGE (410 3710);
FORCEPROP 2 LASTPIN (400 3750) $PN 266
J 0
(410 3760);
DISPLAY 0.617021 (410 3760);
PAINT ORANGE (410 3760);
FORCEPROP 2 LASTPIN (400 3800) $PN 267
J 0
(410 3810);
DISPLAY 0.617021 (410 3810);
PAINT ORANGE (410 3810);
FORCEPROP 2 LASTPIN (400 3850) $PN 277
J 0
(410 3860);
DISPLAY 0.617021 (410 3860);
PAINT ORANGE (410 3860);
FORCEPROP 2 LASTPIN (400 3900) $PN 278
J 0
(410 3910);
DISPLAY 0.617021 (410 3910);
PAINT ORANGE (410 3910);
FORCEPROP 2 LASTPIN (400 3950) $PN 196
J 0
(410 3960);
DISPLAY 0.617021 (410 3960);
PAINT ORANGE (410 3960);
FORCEPROP 2 LASTPIN (400 4000) $PN 197
J 0
(410 4010);
DISPLAY 0.617021 (410 4010);
PAINT ORANGE (410 4010);
FORCEPROP 2 LASTPIN (400 4050) $PN 8
J 0
(410 4060);
DISPLAY 0.617021 (410 4060);
PAINT ORANGE (410 4060);
FORCEPROP 2 LASTPIN (400 4100) $PN 7
J 0
(410 4110);
DISPLAY 0.617021 (410 4110);
PAINT ORANGE (410 4110);
FORCEPROP 2 LASTPIN (400 4150) $PN 19
J 0
(410 4160);
DISPLAY 0.617021 (410 4160);
PAINT ORANGE (410 4160);
FORCEPROP 2 LASTPIN (400 4200) $PN 18
J 0
(410 4210);
DISPLAY 0.617021 (410 4210);
PAINT ORANGE (410 4210);
FORCEPROP 2 LASTPIN (400 4300) $PN 29
J 0
(410 4310);
DISPLAY 0.617021 (410 4310);
PAINT ORANGE (410 4310);
FORCEPROP 2 LASTPIN (400 4350) $PN 41
J 0
(410 4360);
DISPLAY 0.617021 (410 4360);
PAINT ORANGE (410 4360);
FORCEPROP 2 LASTPIN (400 4400) $PN 40
J 0
(410 4410);
DISPLAY 0.617021 (410 4410);
PAINT ORANGE (410 4410);
FORCEPROP 2 LASTPIN (400 4450) $PN 100
J 0
(410 4460);
DISPLAY 0.617021 (410 4460);
PAINT ORANGE (410 4460);
FORCEPROP 2 LASTPIN (400 4500) $PN 99
J 0
(410 4510);
DISPLAY 0.617021 (410 4510);
PAINT ORANGE (410 4510);
FORCEPROP 2 LASTPIN (400 4550) $PN 111
J 0
(410 4560);
DISPLAY 0.617021 (410 4560);
PAINT ORANGE (410 4560);
FORCEPROP 2 LASTPIN (400 4600) $PN 110
J 0
(410 4610);
DISPLAY 0.617021 (410 4610);
PAINT ORANGE (410 4610);
FORCEPROP 2 LASTPIN (400 4650) $PN 122
J 0
(410 4660);
DISPLAY 0.617021 (410 4660);
PAINT ORANGE (410 4660);
FORCEPROP 2 LASTPIN (400 4700) $PN 121
J 0
(410 4710);
DISPLAY 0.617021 (410 4710);
PAINT ORANGE (410 4710);
FORCEPROP 2 LASTPIN (400 4750) $PN 133
J 0
(410 4760);
DISPLAY 0.617021 (410 4760);
PAINT ORANGE (410 4760);
FORCEPROP 2 LASTPIN (400 4800) $PN 132
J 0
(410 4810);
DISPLAY 0.617021 (410 4810);
PAINT ORANGE (410 4810);
FORCEPROP 2 LASTPIN (400 4850) $PN 52
J 0
(410 4860);
DISPLAY 0.617021 (410 4860);
PAINT ORANGE (410 4860);
FORCEPROP 2 LASTPIN (400 4900) $PN 51
J 0
(410 4910);
DISPLAY 0.617021 (410 4910);
PAINT ORANGE (410 4910);
FORCEPROP 1 LAST MATERIAL SCONN
J 0
(-450 5100);
DISPLAY 0.617021 (-450 5100);
PAINT SKYBLUE (-450 5100);
FORCEPROP 1 LAST PART_NUMBER H44441-004
J 0
(-450 2950);
DISPLAY 0.617021 (-450 2950);
PAINT BLUE (-450 2950);
FORCEPROP 1 LAST LOCATION J4G1
J 0
(-450 5150);
DISPLAY 0.617021 (-450 5150);
PAINT AQUA (-450 5150);
FORCEPROP 2 LAST ROOM DDR4_CH_A
J 0
(-50 4050);
PAINT ORANGE (-50 4050);
DISPLAY INVISIBLE (-50 4050);
FORCEPROP 1 LAST PATH I2
J 0
(-50 5100);
PAINT GREEN (-50 5100);
DISPLAY INVISIBLE (-50 5100);
FORCEPROP 2 LAST CDS_LOCATION J4G1
J 0
(-450 5150);
DISPLAY 0.617021 (-450 5150);
PAINT AQUA (-450 5150);
DISPLAY INVISIBLE (-450 5150);
FORCEPROP 2 LAST SEC 2
J 0
(-450 5200);
DISPLAY 0.680851 (-450 5200);
PAINT MONO (-450 5200);
DISPLAY INVISIBLE (-450 5200);
FORCEPROP 2 LAST SEC_TYPE PIP
J 0
(-450 5200);
DISPLAY 1.021277 (-450 5200);
PAINT ORANGE (-450 5200);
DISPLAY INVISIBLE (-450 5200);
FORCEPROP 2 LAST CDS_LIB mstr_sconn
J 0
(-50 4050);
PAINT ORANGE (-50 4050);
DISPLAY INVISIBLE (-50 4050);
FORCEPROP 2 LAST BOM_COST MEM
J 0
(-50 4050);
PAINT ORANGE (-50 4050);
DISPLAY INVISIBLE (-50 4050);
FORCEPROP 1 LAST PACK_TYPE PIP
J 0
(-450 5200);
PAINT SKYBLUE (-450 5200);
DISPLAY INVISIBLE (-450 5200);
FORCEADD TAP..6
R 2
(650 3600);
FORCEPROP 3 LASTPIN (600 3600) SIG_NAME M_A_DQS_DP<4>
J 0
(610 3610);
DISPLAY 0.659574 (610 3610);
PAINT MONO (610 3610);
DISPLAY INVISIBLE (610 3610);
FORCEPROP 1 LASTPIN (600 3600) BN 4
J 2
(650 3610);
DISPLAY 0.617021 (650 3610);
PAINT PINK (650 3610);
FORCEPROP 1 LAST PATH I200
J 2
(650 3600);
DISPLAY 0.936170 (650 3600);
PAINT GREEN (650 3600);
DISPLAY INVISIBLE (650 3600);
FORCEPROP 1 LAST HDL_TAP TRUE
J 2
(325 3475);
DISPLAY 1.234043 (325 3475);
PAINT GREEN (325 3475);
DISPLAY INVISIBLE (325 3475);
FORCEPROP 1 LAST BODY_TYPE PLUMBING
J 2
(650 3550);
DISPLAY 1.234043 (650 3550);
PAINT GREEN (650 3550);
DISPLAY INVISIBLE (650 3550);
FORCEPROP 2 LAST CDS_LIB mstr_standard
J 0
(650 3600);
DISPLAY 0.787234 (650 3600);
PAINT MONO (650 3600);
DISPLAY INVISIBLE (650 3600);
FORCEADD TAP..6
R 2
(650 3200);
FORCEPROP 3 LASTPIN (600 3200) SIG_NAME M_A_DQS_DP<0>
J 0
(610 3210);
DISPLAY 0.659574 (610 3210);
PAINT MONO (610 3210);
DISPLAY INVISIBLE (610 3210);
FORCEPROP 1 LASTPIN (600 3200) BN 0
J 2
(650 3210);
DISPLAY 0.617021 (650 3210);
PAINT PINK (650 3210);
FORCEPROP 1 LAST PATH I201
J 2
(650 3200);
DISPLAY 0.936170 (650 3200);
PAINT GREEN (650 3200);
DISPLAY INVISIBLE (650 3200);
FORCEPROP 1 LAST HDL_TAP TRUE
J 2
(325 3075);
DISPLAY 1.234043 (325 3075);
PAINT GREEN (325 3075);
DISPLAY INVISIBLE (325 3075);
FORCEPROP 1 LAST BODY_TYPE PLUMBING
J 2
(650 3150);
DISPLAY 1.234043 (650 3150);
PAINT GREEN (650 3150);
DISPLAY INVISIBLE (650 3150);
FORCEPROP 2 LAST CDS_LIB mstr_standard
J 0
(650 3200);
DISPLAY 0.787234 (650 3200);
PAINT MONO (650 3200);
DISPLAY INVISIBLE (650 3200);
FORCEADD TAP..6
R 2
(650 3300);
FORCEPROP 3 LASTPIN (600 3300) SIG_NAME M_A_DQS_DP<1>
J 0
(610 3310);
DISPLAY 0.659574 (610 3310);
PAINT MONO (610 3310);
DISPLAY INVISIBLE (610 3310);
FORCEPROP 1 LASTPIN (600 3300) BN 1
J 2
(650 3310);
DISPLAY 0.617021 (650 3310);
PAINT PINK (650 3310);
FORCEPROP 1 LAST PATH I202
J 2
(650 3300);
DISPLAY 0.936170 (650 3300);
PAINT GREEN (650 3300);
DISPLAY INVISIBLE (650 3300);
FORCEPROP 1 LAST HDL_TAP TRUE
J 2
(325 3175);
DISPLAY 1.234043 (325 3175);
PAINT GREEN (325 3175);
DISPLAY INVISIBLE (325 3175);
FORCEPROP 1 LAST BODY_TYPE PLUMBING
J 2
(650 3250);
DISPLAY 1.234043 (650 3250);
PAINT GREEN (650 3250);
DISPLAY INVISIBLE (650 3250);
FORCEPROP 2 LAST CDS_LIB mstr_standard
J 0
(650 3300);
DISPLAY 0.787234 (650 3300);
PAINT MONO (650 3300);
DISPLAY INVISIBLE (650 3300);
FORCEADD TAP..6
R 2
(650 3400);
FORCEPROP 3 LASTPIN (600 3400) SIG_NAME M_A_DQS_DP<2>
J 0
(610 3410);
DISPLAY 0.659574 (610 3410);
PAINT MONO (610 3410);
DISPLAY INVISIBLE (610 3410);
FORCEPROP 1 LASTPIN (600 3400) BN 2
J 2
(650 3410);
DISPLAY 0.617021 (650 3410);
PAINT PINK (650 3410);
FORCEPROP 1 LAST PATH I203
J 2
(650 3400);
DISPLAY 0.936170 (650 3400);
PAINT GREEN (650 3400);
DISPLAY INVISIBLE (650 3400);
FORCEPROP 1 LAST HDL_TAP TRUE
J 2
(325 3275);
DISPLAY 1.234043 (325 3275);
PAINT GREEN (325 3275);
DISPLAY INVISIBLE (325 3275);
FORCEPROP 1 LAST BODY_TYPE PLUMBING
J 2
(650 3350);
DISPLAY 1.234043 (650 3350);
PAINT GREEN (650 3350);
DISPLAY INVISIBLE (650 3350);
FORCEPROP 2 LAST CDS_LIB mstr_standard
J 0
(650 3400);
DISPLAY 0.787234 (650 3400);
PAINT MONO (650 3400);
DISPLAY INVISIBLE (650 3400);
FORCEADD OFFPAGE..3
(1550 4950);
FORCEPROP 2 LAST $XR1 44 
J 0
(1854 4950);
DISPLAY 0.638298 (1854 4950);
PAINT MONO (1854 4950);
FORCEPROP 2 LAST $XR0 23 
J 0
(1764 4950);
DISPLAY 0.638298 (1764 4950);
PAINT MONO (1764 4950);
FORCEPROP 2 LAST PATH I204
J 0
(1750 5025);
DISPLAY 0.787234 (1750 5025);
PAINT MONO (1750 5025);
DISPLAY INVISIBLE (1750 5025);
FORCEPROP 1 LAST COMMENT_BODY TRUE
J 0
(1500 4850);
DISPLAY 0.936170 (1500 4850);
PAINT GREEN (1500 4850);
DISPLAY INVISIBLE (1500 4850);
FORCEPROP 1 LAST OFFPAGE TRUE
J 0
(1875 4825);
DISPLAY 0.936170 (1875 4825);
PAINT GREEN (1875 4825);
DISPLAY INVISIBLE (1875 4825);
FORCEPROP 2 LAST CDS_LIB mstr_standard
J 0
(1550 4950);
DISPLAY 0.787234 (1550 4950);
PAINT MONO (1550 4950);
DISPLAY INVISIBLE (1550 4950);
FORCEADD TAP..6
R 2
(650 4700);
FORCEPROP 3 LASTPIN (600 4700) SIG_NAME M_A_DQS_DP<15>
J 0
(610 4710);
DISPLAY 0.659574 (610 4710);
PAINT MONO (610 4710);
DISPLAY INVISIBLE (610 4710);
FORCEPROP 1 LASTPIN (600 4700) BN 15
J 2
(650 4710);
DISPLAY 0.617021 (650 4710);
PAINT PINK (650 4710);
FORCEPROP 1 LAST PATH I205
J 2
(650 4700);
DISPLAY 0.936170 (650 4700);
PAINT GREEN (650 4700);
DISPLAY INVISIBLE (650 4700);
FORCEPROP 1 LAST HDL_TAP TRUE
J 2
(325 4575);
DISPLAY 1.234043 (325 4575);
PAINT GREEN (325 4575);
DISPLAY INVISIBLE (325 4575);
FORCEPROP 1 LAST BODY_TYPE PLUMBING
J 2
(650 4650);
DISPLAY 1.234043 (650 4650);
PAINT GREEN (650 4650);
DISPLAY INVISIBLE (650 4650);
FORCEPROP 2 LAST CDS_LIB mstr_standard
J 0
(650 4700);
DISPLAY 0.787234 (650 4700);
PAINT MONO (650 4700);
DISPLAY INVISIBLE (650 4700);
FORCEADD TAP..6
R 2
(650 4900);
FORCEPROP 3 LASTPIN (600 4900) SIG_NAME M_A_DQS_DP<17>
J 0
(610 4910);
DISPLAY 0.659574 (610 4910);
PAINT MONO (610 4910);
DISPLAY INVISIBLE (610 4910);
FORCEPROP 1 LASTPIN (600 4900) BN 17
J 2
(650 4910);
DISPLAY 0.617021 (650 4910);
PAINT PINK (650 4910);
FORCEPROP 1 LAST PATH I206
J 2
(650 4900);
DISPLAY 0.936170 (650 4900);
PAINT GREEN (650 4900);
DISPLAY INVISIBLE (650 4900);
FORCEPROP 1 LAST HDL_TAP TRUE
J 2
(325 4775);
DISPLAY 1.234043 (325 4775);
PAINT GREEN (325 4775);
DISPLAY INVISIBLE (325 4775);
FORCEPROP 1 LAST BODY_TYPE PLUMBING
J 2
(650 4850);
DISPLAY 1.234043 (650 4850);
PAINT GREEN (650 4850);
DISPLAY INVISIBLE (650 4850);
FORCEPROP 2 LAST CDS_LIB mstr_standard
J 2
(650 4900);
DISPLAY 0.787234 (650 4900);
PAINT MONO (650 4900);
DISPLAY INVISIBLE (650 4900);
FORCEADD TAP..6
R 2
(650 4800);
FORCEPROP 3 LASTPIN (600 4800) SIG_NAME M_A_DQS_DP<16>
J 0
(610 4810);
DISPLAY 0.659574 (610 4810);
PAINT MONO (610 4810);
DISPLAY INVISIBLE (610 4810);
FORCEPROP 1 LASTPIN (600 4800) BN 16
J 2
(650 4810);
DISPLAY 0.617021 (650 4810);
PAINT PINK (650 4810);
FORCEPROP 1 LAST PATH I207
J 2
(650 4800);
DISPLAY 0.936170 (650 4800);
PAINT GREEN (650 4800);
DISPLAY INVISIBLE (650 4800);
FORCEPROP 1 LAST HDL_TAP TRUE
J 2
(325 4675);
DISPLAY 1.234043 (325 4675);
PAINT GREEN (325 4675);
DISPLAY INVISIBLE (325 4675);
FORCEPROP 1 LAST BODY_TYPE PLUMBING
J 2
(650 4750);
DISPLAY 1.234043 (650 4750);
PAINT GREEN (650 4750);
DISPLAY INVISIBLE (650 4750);
FORCEPROP 2 LAST CDS_LIB mstr_standard
J 0
(650 4800);
DISPLAY 0.787234 (650 4800);
PAINT MONO (650 4800);
DISPLAY INVISIBLE (650 4800);
FORCEADD TAP..6
R 2
(650 4500);
FORCEPROP 3 LASTPIN (600 4500) SIG_NAME M_A_DQS_DP<13>
J 0
(610 4510);
DISPLAY 0.659574 (610 4510);
PAINT MONO (610 4510);
DISPLAY INVISIBLE (610 4510);
FORCEPROP 1 LASTPIN (600 4500) BN 13
J 2
(650 4510);
DISPLAY 0.617021 (650 4510);
PAINT PINK (650 4510);
FORCEPROP 1 LAST PATH I208
J 2
(650 4500);
DISPLAY 0.936170 (650 4500);
PAINT GREEN (650 4500);
DISPLAY INVISIBLE (650 4500);
FORCEPROP 1 LAST HDL_TAP TRUE
J 2
(325 4375);
DISPLAY 1.234043 (325 4375);
PAINT GREEN (325 4375);
DISPLAY INVISIBLE (325 4375);
FORCEPROP 1 LAST BODY_TYPE PLUMBING
J 2
(650 4450);
DISPLAY 1.234043 (650 4450);
PAINT GREEN (650 4450);
DISPLAY INVISIBLE (650 4450);
FORCEPROP 2 LAST CDS_LIB mstr_standard
J 0
(650 4500);
DISPLAY 0.787234 (650 4500);
PAINT MONO (650 4500);
DISPLAY INVISIBLE (650 4500);
FORCEADD TAP..6
R 2
(650 4600);
FORCEPROP 3 LASTPIN (600 4600) SIG_NAME M_A_DQS_DP<14>
J 0
(610 4610);
DISPLAY 0.659574 (610 4610);
PAINT MONO (610 4610);
DISPLAY INVISIBLE (610 4610);
FORCEPROP 1 LASTPIN (600 4600) BN 14
J 2
(650 4610);
DISPLAY 0.617021 (650 4610);
PAINT PINK (650 4610);
FORCEPROP 1 LAST PATH I209
J 2
(650 4600);
DISPLAY 0.936170 (650 4600);
PAINT GREEN (650 4600);
DISPLAY INVISIBLE (650 4600);
FORCEPROP 1 LAST HDL_TAP TRUE
J 2
(325 4475);
DISPLAY 1.234043 (325 4475);
PAINT GREEN (325 4475);
DISPLAY INVISIBLE (325 4475);
FORCEPROP 1 LAST BODY_TYPE PLUMBING
J 2
(650 4550);
DISPLAY 1.234043 (650 4550);
PAINT GREEN (650 4550);
DISPLAY INVISIBLE (650 4550);
FORCEPROP 2 LAST CDS_LIB mstr_standard
J 0
(650 4600);
DISPLAY 0.787234 (650 4600);
PAINT MONO (650 4600);
DISPLAY INVISIBLE (650 4600);
FORCEADD TAP..6
R 2
(650 4400);
FORCEPROP 3 LASTPIN (600 4400) SIG_NAME M_A_DQS_DP<12>
J 0
(610 4410);
DISPLAY 0.659574 (610 4410);
PAINT MONO (610 4410);
DISPLAY INVISIBLE (610 4410);
FORCEPROP 1 LASTPIN (600 4400) BN 12
J 2
(650 4410);
DISPLAY 0.617021 (650 4410);
PAINT PINK (650 4410);
FORCEPROP 1 LAST PATH I210
J 2
(650 4400);
DISPLAY 0.936170 (650 4400);
PAINT GREEN (650 4400);
DISPLAY INVISIBLE (650 4400);
FORCEPROP 1 LAST HDL_TAP TRUE
J 2
(325 4275);
DISPLAY 1.234043 (325 4275);
PAINT GREEN (325 4275);
DISPLAY INVISIBLE (325 4275);
FORCEPROP 1 LAST BODY_TYPE PLUMBING
J 2
(650 4350);
DISPLAY 1.234043 (650 4350);
PAINT GREEN (650 4350);
DISPLAY INVISIBLE (650 4350);
FORCEPROP 2 LAST CDS_LIB mstr_standard
J 0
(650 4400);
DISPLAY 0.787234 (650 4400);
PAINT MONO (650 4400);
DISPLAY INVISIBLE (650 4400);
FORCEADD OFFPAGE..3
(1550 4900);
FORCEPROP 2 LAST $XR1 44 
J 0
(1854 4900);
DISPLAY 0.638298 (1854 4900);
PAINT MONO (1854 4900);
FORCEPROP 2 LAST $XR0 23 
J 0
(1764 4900);
DISPLAY 0.638298 (1764 4900);
PAINT MONO (1764 4900);
FORCEPROP 2 LAST PATH I211
J 0
(1750 4975);
DISPLAY 0.787234 (1750 4975);
PAINT MONO (1750 4975);
DISPLAY INVISIBLE (1750 4975);
FORCEPROP 1 LAST COMMENT_BODY TRUE
J 0
(1500 4800);
DISPLAY 0.936170 (1500 4800);
PAINT GREEN (1500 4800);
DISPLAY INVISIBLE (1500 4800);
FORCEPROP 1 LAST OFFPAGE TRUE
J 0
(1875 4775);
DISPLAY 0.936170 (1875 4775);
PAINT GREEN (1875 4775);
DISPLAY INVISIBLE (1875 4775);
FORCEPROP 2 LAST CDS_LIB mstr_standard
J 0
(1550 4900);
DISPLAY 0.787234 (1550 4900);
PAINT MONO (1550 4900);
DISPLAY INVISIBLE (1550 4900);
FORCEADD TAP..6
R 2
(850 4850);
FORCEPROP 3 LASTPIN (800 4850) SIG_NAME M_A_DQS_DN<17>
J 0
(810 4860);
DISPLAY 0.659574 (810 4860);
PAINT MONO (810 4860);
DISPLAY INVISIBLE (810 4860);
FORCEPROP 1 LASTPIN (800 4850) BN 17
J 2
(850 4860);
DISPLAY 0.617021 (850 4860);
PAINT PINK (850 4860);
FORCEPROP 1 LAST PATH I212
J 2
(850 4850);
DISPLAY 0.936170 (850 4850);
PAINT GREEN (850 4850);
DISPLAY INVISIBLE (850 4850);
FORCEPROP 1 LAST HDL_TAP TRUE
J 2
(525 4725);
DISPLAY 1.234043 (525 4725);
PAINT GREEN (525 4725);
DISPLAY INVISIBLE (525 4725);
FORCEPROP 1 LAST BODY_TYPE PLUMBING
J 2
(850 4800);
DISPLAY 1.234043 (850 4800);
PAINT GREEN (850 4800);
DISPLAY INVISIBLE (850 4800);
FORCEPROP 2 LAST CDS_LIB mstr_standard
J 2
(850 4850);
DISPLAY 0.787234 (850 4850);
PAINT MONO (850 4850);
DISPLAY INVISIBLE (850 4850);
FORCEADD TAP..6
R 2
(850 4750);
FORCEPROP 3 LASTPIN (800 4750) SIG_NAME M_A_DQS_DN<16>
J 0
(810 4760);
DISPLAY 0.659574 (810 4760);
PAINT MONO (810 4760);
DISPLAY INVISIBLE (810 4760);
FORCEPROP 1 LASTPIN (800 4750) BN 16
J 2
(850 4760);
DISPLAY 0.617021 (850 4760);
PAINT PINK (850 4760);
FORCEPROP 1 LAST PATH I213
J 2
(850 4750);
DISPLAY 0.936170 (850 4750);
PAINT GREEN (850 4750);
DISPLAY INVISIBLE (850 4750);
FORCEPROP 1 LAST HDL_TAP TRUE
J 2
(525 4625);
DISPLAY 1.234043 (525 4625);
PAINT GREEN (525 4625);
DISPLAY INVISIBLE (525 4625);
FORCEPROP 1 LAST BODY_TYPE PLUMBING
J 2
(850 4700);
DISPLAY 1.234043 (850 4700);
PAINT GREEN (850 4700);
DISPLAY INVISIBLE (850 4700);
FORCEPROP 2 LAST CDS_LIB mstr_standard
J 0
(850 4750);
DISPLAY 0.787234 (850 4750);
PAINT MONO (850 4750);
DISPLAY INVISIBLE (850 4750);
FORCEADD TAP..6
R 2
(850 4650);
FORCEPROP 3 LASTPIN (800 4650) SIG_NAME M_A_DQS_DN<15>
J 0
(810 4660);
DISPLAY 0.659574 (810 4660);
PAINT MONO (810 4660);
DISPLAY INVISIBLE (810 4660);
FORCEPROP 1 LASTPIN (800 4650) BN 15
J 2
(850 4660);
DISPLAY 0.617021 (850 4660);
PAINT PINK (850 4660);
FORCEPROP 1 LAST PATH I214
J 2
(850 4650);
DISPLAY 0.936170 (850 4650);
PAINT GREEN (850 4650);
DISPLAY INVISIBLE (850 4650);
FORCEPROP 1 LAST HDL_TAP TRUE
J 2
(525 4525);
DISPLAY 1.234043 (525 4525);
PAINT GREEN (525 4525);
DISPLAY INVISIBLE (525 4525);
FORCEPROP 1 LAST BODY_TYPE PLUMBING
J 2
(850 4600);
DISPLAY 1.234043 (850 4600);
PAINT GREEN (850 4600);
DISPLAY INVISIBLE (850 4600);
FORCEPROP 2 LAST CDS_LIB mstr_standard
J 0
(850 4650);
DISPLAY 0.787234 (850 4650);
PAINT MONO (850 4650);
DISPLAY INVISIBLE (850 4650);
FORCEADD TAP..6
R 2
(850 4550);
FORCEPROP 3 LASTPIN (800 4550) SIG_NAME M_A_DQS_DN<14>
J 0
(810 4560);
DISPLAY 0.659574 (810 4560);
PAINT MONO (810 4560);
DISPLAY INVISIBLE (810 4560);
FORCEPROP 1 LASTPIN (800 4550) BN 14
J 2
(850 4560);
DISPLAY 0.617021 (850 4560);
PAINT PINK (850 4560);
FORCEPROP 1 LAST PATH I215
J 2
(850 4550);
DISPLAY 0.936170 (850 4550);
PAINT GREEN (850 4550);
DISPLAY INVISIBLE (850 4550);
FORCEPROP 1 LAST HDL_TAP TRUE
J 2
(525 4425);
DISPLAY 1.234043 (525 4425);
PAINT GREEN (525 4425);
DISPLAY INVISIBLE (525 4425);
FORCEPROP 1 LAST BODY_TYPE PLUMBING
J 2
(850 4500);
DISPLAY 1.234043 (850 4500);
PAINT GREEN (850 4500);
DISPLAY INVISIBLE (850 4500);
FORCEPROP 2 LAST CDS_LIB mstr_standard
J 0
(850 4550);
DISPLAY 0.787234 (850 4550);
PAINT MONO (850 4550);
DISPLAY INVISIBLE (850 4550);
FORCEADD TAP..6
R 2
(850 4450);
FORCEPROP 3 LASTPIN (800 4450) SIG_NAME M_A_DQS_DN<13>
J 0
(810 4460);
DISPLAY 0.659574 (810 4460);
PAINT MONO (810 4460);
DISPLAY INVISIBLE (810 4460);
FORCEPROP 1 LASTPIN (800 4450) BN 13
J 2
(850 4460);
DISPLAY 0.617021 (850 4460);
PAINT PINK (850 4460);
FORCEPROP 1 LAST PATH I216
J 2
(850 4450);
DISPLAY 0.936170 (850 4450);
PAINT GREEN (850 4450);
DISPLAY INVISIBLE (850 4450);
FORCEPROP 1 LAST HDL_TAP TRUE
J 2
(525 4325);
DISPLAY 1.234043 (525 4325);
PAINT GREEN (525 4325);
DISPLAY INVISIBLE (525 4325);
FORCEPROP 1 LAST BODY_TYPE PLUMBING
J 2
(850 4400);
DISPLAY 1.234043 (850 4400);
PAINT GREEN (850 4400);
DISPLAY INVISIBLE (850 4400);
FORCEPROP 2 LAST CDS_LIB mstr_standard
J 0
(850 4450);
DISPLAY 0.787234 (850 4450);
PAINT MONO (850 4450);
DISPLAY INVISIBLE (850 4450);
FORCEADD TAP..6
R 2
(850 4350);
FORCEPROP 3 LASTPIN (800 4350) SIG_NAME M_A_DQS_DN<12>
J 0
(810 4360);
DISPLAY 0.659574 (810 4360);
PAINT MONO (810 4360);
DISPLAY INVISIBLE (810 4360);
FORCEPROP 1 LASTPIN (800 4350) BN 12
J 2
(850 4360);
DISPLAY 0.617021 (850 4360);
PAINT PINK (850 4360);
FORCEPROP 1 LAST PATH I217
J 2
(850 4350);
DISPLAY 0.936170 (850 4350);
PAINT GREEN (850 4350);
DISPLAY INVISIBLE (850 4350);
FORCEPROP 1 LAST HDL_TAP TRUE
J 2
(525 4225);
DISPLAY 1.234043 (525 4225);
PAINT GREEN (525 4225);
DISPLAY INVISIBLE (525 4225);
FORCEPROP 1 LAST BODY_TYPE PLUMBING
J 2
(850 4300);
DISPLAY 1.234043 (850 4300);
PAINT GREEN (850 4300);
DISPLAY INVISIBLE (850 4300);
FORCEPROP 2 LAST CDS_LIB mstr_standard
J 0
(850 4350);
DISPLAY 0.787234 (850 4350);
PAINT MONO (850 4350);
DISPLAY INVISIBLE (850 4350);
FORCEADD TAP..6
R 2
(850 4250);
FORCEPROP 3 LASTPIN (800 4250) SIG_NAME M_A_DQS_DN<11>
J 0
(810 4260);
DISPLAY 0.659574 (810 4260);
PAINT MONO (810 4260);
DISPLAY INVISIBLE (810 4260);
FORCEPROP 1 LASTPIN (800 4250) BN 11
J 2
(850 4260);
DISPLAY 0.617021 (850 4260);
PAINT PINK (850 4260);
FORCEPROP 1 LAST PATH I218
J 2
(850 4250);
DISPLAY 0.936170 (850 4250);
PAINT GREEN (850 4250);
DISPLAY INVISIBLE (850 4250);
FORCEPROP 1 LAST HDL_TAP TRUE
J 2
(525 4125);
DISPLAY 1.234043 (525 4125);
PAINT GREEN (525 4125);
DISPLAY INVISIBLE (525 4125);
FORCEPROP 1 LAST BODY_TYPE PLUMBING
J 2
(850 4200);
DISPLAY 1.234043 (850 4200);
PAINT GREEN (850 4200);
DISPLAY INVISIBLE (850 4200);
FORCEPROP 2 LAST CDS_LIB mstr_standard
J 0
(850 4250);
DISPLAY 0.787234 (850 4250);
PAINT MONO (850 4250);
DISPLAY INVISIBLE (850 4250);
FORCEADD TAP..6
R 2
(850 4150);
FORCEPROP 3 LASTPIN (800 4150) SIG_NAME M_A_DQS_DN<10>
J 0
(810 4160);
DISPLAY 0.659574 (810 4160);
PAINT MONO (810 4160);
DISPLAY INVISIBLE (810 4160);
FORCEPROP 1 LASTPIN (800 4150) BN 10
J 2
(850 4160);
DISPLAY 0.617021 (850 4160);
PAINT PINK (850 4160);
FORCEPROP 1 LAST PATH I219
J 2
(850 4150);
DISPLAY 0.936170 (850 4150);
PAINT GREEN (850 4150);
DISPLAY INVISIBLE (850 4150);
FORCEPROP 1 LAST HDL_TAP TRUE
J 2
(525 4025);
DISPLAY 1.234043 (525 4025);
PAINT GREEN (525 4025);
DISPLAY INVISIBLE (525 4025);
FORCEPROP 1 LAST BODY_TYPE PLUMBING
J 2
(850 4100);
DISPLAY 1.234043 (850 4100);
PAINT GREEN (850 4100);
DISPLAY INVISIBLE (850 4100);
FORCEPROP 2 LAST CDS_LIB mstr_standard
J 0
(850 4150);
DISPLAY 0.787234 (850 4150);
PAINT MONO (850 4150);
DISPLAY INVISIBLE (850 4150);
FORCEADD TAP..6
(-3150 4400);
FORCEPROP 3 LASTPIN (-3100 4400) SIG_NAME M_A_MA<17>
J 0
(-3090 4410);
DISPLAY 0.659574 (-3090 4410);
PAINT MONO (-3090 4410);
DISPLAY INVISIBLE (-3090 4410);
FORCEPROP 1 LASTPIN (-3100 4400) BN 17
J 0
(-3150 4410);
DISPLAY 0.617021 (-3150 4410);
PAINT PINK (-3150 4410);
FORCEPROP 1 LAST PATH I22
J 0
(-3150 4400);
DISPLAY 0.936170 (-3150 4400);
PAINT GREEN (-3150 4400);
DISPLAY INVISIBLE (-3150 4400);
FORCEPROP 1 LAST HDL_TAP TRUE
J 0
(-2825 4275);
DISPLAY 1.234043 (-2825 4275);
PAINT GREEN (-2825 4275);
DISPLAY INVISIBLE (-2825 4275);
FORCEPROP 1 LAST BODY_TYPE PLUMBING
J 0
(-3150 4350);
DISPLAY 1.234043 (-3150 4350);
PAINT GREEN (-3150 4350);
DISPLAY INVISIBLE (-3150 4350);
FORCEPROP 2 LAST CDS_LIB mstr_standard
J 0
(-3150 4400);
DISPLAY 0.787234 (-3150 4400);
PAINT MONO (-3150 4400);
DISPLAY INVISIBLE (-3150 4400);
FORCEADD TAP..6
R 2
(850 4050);
FORCEPROP 3 LASTPIN (800 4050) SIG_NAME M_A_DQS_DN<9>
J 0
(810 4060);
DISPLAY 0.659574 (810 4060);
PAINT MONO (810 4060);
DISPLAY INVISIBLE (810 4060);
FORCEPROP 1 LASTPIN (800 4050) BN 9
J 2
(850 4060);
DISPLAY 0.617021 (850 4060);
PAINT PINK (850 4060);
FORCEPROP 1 LAST PATH I220
J 2
(850 4050);
DISPLAY 0.936170 (850 4050);
PAINT GREEN (850 4050);
DISPLAY INVISIBLE (850 4050);
FORCEPROP 1 LAST HDL_TAP TRUE
J 2
(525 3925);
DISPLAY 1.234043 (525 3925);
PAINT GREEN (525 3925);
DISPLAY INVISIBLE (525 3925);
FORCEPROP 1 LAST BODY_TYPE PLUMBING
J 2
(850 4000);
DISPLAY 1.234043 (850 4000);
PAINT GREEN (850 4000);
DISPLAY INVISIBLE (850 4000);
FORCEPROP 2 LAST CDS_LIB mstr_standard
J 0
(850 4050);
DISPLAY 0.787234 (850 4050);
PAINT MONO (850 4050);
DISPLAY INVISIBLE (850 4050);
FORCEADD TAP..6
R 2
(850 3950);
FORCEPROP 3 LASTPIN (800 3950) SIG_NAME M_A_DQS_DN<8>
J 0
(810 3960);
DISPLAY 0.659574 (810 3960);
PAINT MONO (810 3960);
DISPLAY INVISIBLE (810 3960);
FORCEPROP 1 LASTPIN (800 3950) BN 8
J 2
(850 3960);
DISPLAY 0.617021 (850 3960);
PAINT PINK (850 3960);
FORCEPROP 1 LAST PATH I221
J 2
(850 3950);
DISPLAY 0.936170 (850 3950);
PAINT GREEN (850 3950);
DISPLAY INVISIBLE (850 3950);
FORCEPROP 1 LAST HDL_TAP TRUE
J 2
(525 3825);
DISPLAY 1.234043 (525 3825);
PAINT GREEN (525 3825);
DISPLAY INVISIBLE (525 3825);
FORCEPROP 1 LAST BODY_TYPE PLUMBING
J 2
(850 3900);
DISPLAY 1.234043 (850 3900);
PAINT GREEN (850 3900);
DISPLAY INVISIBLE (850 3900);
FORCEPROP 2 LAST CDS_LIB mstr_standard
J 0
(850 3950);
DISPLAY 0.787234 (850 3950);
PAINT MONO (850 3950);
DISPLAY INVISIBLE (850 3950);
FORCEADD TAP..6
R 2
(850 3850);
FORCEPROP 3 LASTPIN (800 3850) SIG_NAME M_A_DQS_DN<7>
J 0
(810 3860);
DISPLAY 0.659574 (810 3860);
PAINT MONO (810 3860);
DISPLAY INVISIBLE (810 3860);
FORCEPROP 1 LASTPIN (800 3850) BN 7
J 2
(850 3860);
DISPLAY 0.617021 (850 3860);
PAINT PINK (850 3860);
FORCEPROP 1 LAST PATH I222
J 2
(850 3850);
DISPLAY 0.936170 (850 3850);
PAINT GREEN (850 3850);
DISPLAY INVISIBLE (850 3850);
FORCEPROP 1 LAST HDL_TAP TRUE
J 2
(525 3725);
DISPLAY 1.234043 (525 3725);
PAINT GREEN (525 3725);
DISPLAY INVISIBLE (525 3725);
FORCEPROP 1 LAST BODY_TYPE PLUMBING
J 2
(850 3800);
DISPLAY 1.234043 (850 3800);
PAINT GREEN (850 3800);
DISPLAY INVISIBLE (850 3800);
FORCEPROP 2 LAST CDS_LIB mstr_standard
J 0
(850 3850);
DISPLAY 0.787234 (850 3850);
PAINT MONO (850 3850);
DISPLAY INVISIBLE (850 3850);
FORCEADD TAP..6
R 2
(850 3750);
FORCEPROP 3 LASTPIN (800 3750) SIG_NAME M_A_DQS_DN<6>
J 0
(810 3760);
DISPLAY 0.659574 (810 3760);
PAINT MONO (810 3760);
DISPLAY INVISIBLE (810 3760);
FORCEPROP 1 LASTPIN (800 3750) BN 6
J 2
(850 3760);
DISPLAY 0.617021 (850 3760);
PAINT PINK (850 3760);
FORCEPROP 1 LAST PATH I223
J 2
(850 3750);
DISPLAY 0.936170 (850 3750);
PAINT GREEN (850 3750);
DISPLAY INVISIBLE (850 3750);
FORCEPROP 1 LAST HDL_TAP TRUE
J 2
(525 3625);
DISPLAY 1.234043 (525 3625);
PAINT GREEN (525 3625);
DISPLAY INVISIBLE (525 3625);
FORCEPROP 1 LAST BODY_TYPE PLUMBING
J 2
(850 3700);
DISPLAY 1.234043 (850 3700);
PAINT GREEN (850 3700);
DISPLAY INVISIBLE (850 3700);
FORCEPROP 2 LAST CDS_LIB mstr_standard
J 0
(850 3750);
DISPLAY 0.787234 (850 3750);
PAINT MONO (850 3750);
DISPLAY INVISIBLE (850 3750);
FORCEADD TAP..6
R 2
(850 3650);
FORCEPROP 3 LASTPIN (800 3650) SIG_NAME M_A_DQS_DN<5>
J 0
(810 3660);
DISPLAY 0.659574 (810 3660);
PAINT MONO (810 3660);
DISPLAY INVISIBLE (810 3660);
FORCEPROP 1 LASTPIN (800 3650) BN 5
J 2
(850 3660);
DISPLAY 0.617021 (850 3660);
PAINT PINK (850 3660);
FORCEPROP 1 LAST PATH I224
J 2
(850 3650);
DISPLAY 0.936170 (850 3650);
PAINT GREEN (850 3650);
DISPLAY INVISIBLE (850 3650);
FORCEPROP 1 LAST HDL_TAP TRUE
J 2
(525 3525);
DISPLAY 1.234043 (525 3525);
PAINT GREEN (525 3525);
DISPLAY INVISIBLE (525 3525);
FORCEPROP 1 LAST BODY_TYPE PLUMBING
J 2
(850 3600);
DISPLAY 1.234043 (850 3600);
PAINT GREEN (850 3600);
DISPLAY INVISIBLE (850 3600);
FORCEPROP 2 LAST CDS_LIB mstr_standard
J 0
(850 3650);
DISPLAY 0.787234 (850 3650);
PAINT MONO (850 3650);
DISPLAY INVISIBLE (850 3650);
FORCEADD TAP..6
R 2
(850 3550);
FORCEPROP 3 LASTPIN (800 3550) SIG_NAME M_A_DQS_DN<4>
J 0
(810 3560);
DISPLAY 0.659574 (810 3560);
PAINT MONO (810 3560);
DISPLAY INVISIBLE (810 3560);
FORCEPROP 1 LASTPIN (800 3550) BN 4
J 2
(850 3560);
DISPLAY 0.617021 (850 3560);
PAINT PINK (850 3560);
FORCEPROP 1 LAST PATH I225
J 2
(850 3550);
DISPLAY 0.936170 (850 3550);
PAINT GREEN (850 3550);
DISPLAY INVISIBLE (850 3550);
FORCEPROP 1 LAST HDL_TAP TRUE
J 2
(525 3425);
DISPLAY 1.234043 (525 3425);
PAINT GREEN (525 3425);
DISPLAY INVISIBLE (525 3425);
FORCEPROP 1 LAST BODY_TYPE PLUMBING
J 2
(850 3500);
DISPLAY 1.234043 (850 3500);
PAINT GREEN (850 3500);
DISPLAY INVISIBLE (850 3500);
FORCEPROP 2 LAST CDS_LIB mstr_standard
J 0
(850 3550);
DISPLAY 0.787234 (850 3550);
PAINT MONO (850 3550);
DISPLAY INVISIBLE (850 3550);
FORCEADD TAP..6
R 2
(850 3450);
FORCEPROP 3 LASTPIN (800 3450) SIG_NAME M_A_DQS_DN<3>
J 0
(810 3460);
DISPLAY 0.659574 (810 3460);
PAINT MONO (810 3460);
DISPLAY INVISIBLE (810 3460);
FORCEPROP 1 LASTPIN (800 3450) BN 3
J 2
(850 3460);
DISPLAY 0.617021 (850 3460);
PAINT PINK (850 3460);
FORCEPROP 1 LAST PATH I226
J 2
(850 3450);
DISPLAY 0.936170 (850 3450);
PAINT GREEN (850 3450);
DISPLAY INVISIBLE (850 3450);
FORCEPROP 1 LAST HDL_TAP TRUE
J 2
(525 3325);
DISPLAY 1.234043 (525 3325);
PAINT GREEN (525 3325);
DISPLAY INVISIBLE (525 3325);
FORCEPROP 1 LAST BODY_TYPE PLUMBING
J 2
(850 3400);
DISPLAY 1.234043 (850 3400);
PAINT GREEN (850 3400);
DISPLAY INVISIBLE (850 3400);
FORCEPROP 2 LAST CDS_LIB mstr_standard
J 0
(850 3450);
DISPLAY 0.787234 (850 3450);
PAINT MONO (850 3450);
DISPLAY INVISIBLE (850 3450);
FORCEADD TAP..6
R 2
(850 3350);
FORCEPROP 3 LASTPIN (800 3350) SIG_NAME M_A_DQS_DN<2>
J 0
(810 3360);
DISPLAY 0.659574 (810 3360);
PAINT MONO (810 3360);
DISPLAY INVISIBLE (810 3360);
FORCEPROP 1 LASTPIN (800 3350) BN 2
J 2
(850 3360);
DISPLAY 0.617021 (850 3360);
PAINT PINK (850 3360);
FORCEPROP 1 LAST PATH I227
J 2
(850 3350);
DISPLAY 0.936170 (850 3350);
PAINT GREEN (850 3350);
DISPLAY INVISIBLE (850 3350);
FORCEPROP 1 LAST HDL_TAP TRUE
J 2
(525 3225);
DISPLAY 1.234043 (525 3225);
PAINT GREEN (525 3225);
DISPLAY INVISIBLE (525 3225);
FORCEPROP 1 LAST BODY_TYPE PLUMBING
J 2
(850 3300);
DISPLAY 1.234043 (850 3300);
PAINT GREEN (850 3300);
DISPLAY INVISIBLE (850 3300);
FORCEPROP 2 LAST CDS_LIB mstr_standard
J 0
(850 3350);
DISPLAY 0.787234 (850 3350);
PAINT MONO (850 3350);
DISPLAY INVISIBLE (850 3350);
FORCEADD TAP..6
R 2
(850 3250);
FORCEPROP 3 LASTPIN (800 3250) SIG_NAME M_A_DQS_DN<1>
J 0
(810 3260);
DISPLAY 0.659574 (810 3260);
PAINT MONO (810 3260);
DISPLAY INVISIBLE (810 3260);
FORCEPROP 1 LASTPIN (800 3250) BN 1
J 2
(850 3260);
DISPLAY 0.617021 (850 3260);
PAINT PINK (850 3260);
FORCEPROP 1 LAST PATH I228
J 2
(850 3250);
DISPLAY 0.936170 (850 3250);
PAINT GREEN (850 3250);
DISPLAY INVISIBLE (850 3250);
FORCEPROP 1 LAST HDL_TAP TRUE
J 2
(525 3125);
DISPLAY 1.234043 (525 3125);
PAINT GREEN (525 3125);
DISPLAY INVISIBLE (525 3125);
FORCEPROP 1 LAST BODY_TYPE PLUMBING
J 2
(850 3200);
DISPLAY 1.234043 (850 3200);
PAINT GREEN (850 3200);
DISPLAY INVISIBLE (850 3200);
FORCEPROP 2 LAST CDS_LIB mstr_standard
J 0
(850 3250);
DISPLAY 0.787234 (850 3250);
PAINT MONO (850 3250);
DISPLAY INVISIBLE (850 3250);
FORCEADD TAP..6
R 2
(850 3150);
FORCEPROP 3 LASTPIN (800 3150) SIG_NAME M_A_DQS_DN<0>
J 0
(810 3160);
DISPLAY 0.659574 (810 3160);
PAINT MONO (810 3160);
DISPLAY INVISIBLE (810 3160);
FORCEPROP 1 LASTPIN (800 3150) BN 0
J 2
(850 3160);
DISPLAY 0.617021 (850 3160);
PAINT PINK (850 3160);
FORCEPROP 1 LAST PATH I229
J 2
(850 3150);
DISPLAY 0.936170 (850 3150);
PAINT GREEN (850 3150);
DISPLAY INVISIBLE (850 3150);
FORCEPROP 1 LAST HDL_TAP TRUE
J 2
(525 3025);
DISPLAY 1.234043 (525 3025);
PAINT GREEN (525 3025);
DISPLAY INVISIBLE (525 3025);
FORCEPROP 1 LAST BODY_TYPE PLUMBING
J 2
(850 3100);
DISPLAY 1.234043 (850 3100);
PAINT GREEN (850 3100);
DISPLAY INVISIBLE (850 3100);
FORCEPROP 2 LAST CDS_LIB mstr_standard
J 0
(850 3150);
DISPLAY 0.787234 (850 3150);
PAINT MONO (850 3150);
DISPLAY INVISIBLE (850 3150);
FORCEADD TAP..6
(-3150 4350);
FORCEPROP 3 LASTPIN (-3100 4350) SIG_NAME M_A_MA<16>
J 0
(-3090 4360);
DISPLAY 0.659574 (-3090 4360);
PAINT MONO (-3090 4360);
DISPLAY INVISIBLE (-3090 4360);
FORCEPROP 1 LASTPIN (-3100 4350) BN 16
J 0
(-3150 4360);
DISPLAY 0.617021 (-3150 4360);
PAINT PINK (-3150 4360);
FORCEPROP 1 LAST PATH I23
J 0
(-3150 4350);
DISPLAY 0.936170 (-3150 4350);
PAINT GREEN (-3150 4350);
DISPLAY INVISIBLE (-3150 4350);
FORCEPROP 1 LAST HDL_TAP TRUE
J 0
(-2825 4225);
DISPLAY 1.234043 (-2825 4225);
PAINT GREEN (-2825 4225);
DISPLAY INVISIBLE (-2825 4225);
FORCEPROP 1 LAST BODY_TYPE PLUMBING
J 0
(-3150 4300);
DISPLAY 1.234043 (-3150 4300);
PAINT GREEN (-3150 4300);
DISPLAY INVISIBLE (-3150 4300);
FORCEPROP 2 LAST CDS_LIB mstr_standard
J 2
(-3150 4350);
DISPLAY 0.787234 (-3150 4350);
PAINT MONO (-3150 4350);
DISPLAY INVISIBLE (-3150 4350);
FORCEADD TAP..6
(-3150 2450);
FORCEPROP 3 LASTPIN (-3100 2450) SIG_NAME M_A_ODT<0>
J 0
(-3090 2460);
DISPLAY 0.659574 (-3090 2460);
PAINT MONO (-3090 2460);
DISPLAY INVISIBLE (-3090 2460);
FORCEPROP 1 LASTPIN (-3100 2450) BN 0
J 0
(-3150 2460);
DISPLAY 0.617021 (-3150 2460);
PAINT PINK (-3150 2460);
FORCEPROP 1 LAST PATH I235
J 0
(-3150 2450);
DISPLAY 0.936170 (-3150 2450);
PAINT GREEN (-3150 2450);
DISPLAY INVISIBLE (-3150 2450);
FORCEPROP 1 LAST HDL_TAP TRUE
J 0
(-2825 2325);
DISPLAY 1.234043 (-2825 2325);
PAINT GREEN (-2825 2325);
DISPLAY INVISIBLE (-2825 2325);
FORCEPROP 1 LAST BODY_TYPE PLUMBING
J 0
(-3150 2400);
DISPLAY 1.234043 (-3150 2400);
PAINT GREEN (-3150 2400);
DISPLAY INVISIBLE (-3150 2400);
FORCEPROP 2 LAST CDS_LIB mstr_standard
J 0
(-3150 2450);
DISPLAY 0.787234 (-3150 2450);
PAINT MONO (-3150 2450);
DISPLAY INVISIBLE (-3150 2450);
FORCEADD TAP..6
(-3150 2500);
FORCEPROP 3 LASTPIN (-3100 2500) SIG_NAME M_A_ODT<1>
J 0
(-3090 2510);
DISPLAY 0.659574 (-3090 2510);
PAINT MONO (-3090 2510);
DISPLAY INVISIBLE (-3090 2510);
FORCEPROP 1 LASTPIN (-3100 2500) BN 1
J 0
(-3150 2510);
DISPLAY 0.617021 (-3150 2510);
PAINT PINK (-3150 2510);
FORCEPROP 1 LAST PATH I236
J 0
(-3150 2500);
DISPLAY 0.936170 (-3150 2500);
PAINT GREEN (-3150 2500);
DISPLAY INVISIBLE (-3150 2500);
FORCEPROP 1 LAST HDL_TAP TRUE
J 0
(-2825 2375);
DISPLAY 1.234043 (-2825 2375);
PAINT GREEN (-2825 2375);
DISPLAY INVISIBLE (-2825 2375);
FORCEPROP 1 LAST BODY_TYPE PLUMBING
J 0
(-3150 2450);
DISPLAY 1.234043 (-3150 2450);
PAINT GREEN (-3150 2450);
DISPLAY INVISIBLE (-3150 2450);
FORCEPROP 2 LAST CDS_LIB mstr_standard
J 0
(-3150 2500);
DISPLAY 0.787234 (-3150 2500);
PAINT MONO (-3150 2500);
DISPLAY INVISIBLE (-3150 2500);
FORCEADD OFFPAGE..1
(-3800 2550);
FORCEPROP 2 LAST $XR1 44 
J 0
(-4111 2550);
DISPLAY 0.638298 (-4111 2550);
PAINT MONO (-4111 2550);
FORCEPROP 2 LAST $XR0 23 
J 0
(-4021 2550);
DISPLAY 0.638298 (-4021 2550);
PAINT MONO (-4021 2550);
FORCEPROP 2 LAST PATH I237
J 0
(-3750 2625);
DISPLAY 0.787234 (-3750 2625);
PAINT MONO (-3750 2625);
DISPLAY INVISIBLE (-3750 2625);
FORCEPROP 1 LAST COMMENT_BODY TRUE
J 0
(-3675 2450);
DISPLAY 0.936170 (-3675 2450);
PAINT GREEN (-3675 2450);
DISPLAY INVISIBLE (-3675 2450);
FORCEPROP 1 LAST OFFPAGE TRUE
J 0
(-3475 2425);
DISPLAY 0.936170 (-3475 2425);
PAINT GREEN (-3475 2425);
DISPLAY INVISIBLE (-3475 2425);
FORCEPROP 2 LAST CDS_LIB mstr_standard
J 0
(-3800 2550);
DISPLAY 0.787234 (-3800 2550);
PAINT MONO (-3800 2550);
DISPLAY INVISIBLE (-3800 2550);
FORCEADD TAP..6
(-3150 2650);
FORCEPROP 3 LASTPIN (-3100 2650) SIG_NAME M_A_CKE<1>
J 0
(-3090 2660);
DISPLAY 0.659574 (-3090 2660);
PAINT MONO (-3090 2660);
DISPLAY INVISIBLE (-3090 2660);
FORCEPROP 1 LASTPIN (-3100 2650) BN 1
J 0
(-3150 2660);
DISPLAY 0.617021 (-3150 2660);
PAINT PINK (-3150 2660);
FORCEPROP 1 LAST PATH I238
J 0
(-3150 2650);
DISPLAY 0.936170 (-3150 2650);
PAINT GREEN (-3150 2650);
DISPLAY INVISIBLE (-3150 2650);
FORCEPROP 1 LAST HDL_TAP TRUE
J 0
(-2825 2525);
DISPLAY 1.234043 (-2825 2525);
PAINT GREEN (-2825 2525);
DISPLAY INVISIBLE (-2825 2525);
FORCEPROP 1 LAST BODY_TYPE PLUMBING
J 0
(-3150 2600);
DISPLAY 1.234043 (-3150 2600);
PAINT GREEN (-3150 2600);
DISPLAY INVISIBLE (-3150 2600);
FORCEPROP 2 LAST CDS_LIB mstr_standard
J 0
(-3150 2650);
DISPLAY 0.787234 (-3150 2650);
PAINT MONO (-3150 2650);
DISPLAY INVISIBLE (-3150 2650);
FORCEADD TAP..6
(-3150 2600);
FORCEPROP 3 LASTPIN (-3100 2600) SIG_NAME M_A_CKE<0>
J 0
(-3090 2610);
DISPLAY 0.659574 (-3090 2610);
PAINT MONO (-3090 2610);
DISPLAY INVISIBLE (-3090 2610);
FORCEPROP 1 LASTPIN (-3100 2600) BN 0
J 0
(-3150 2610);
DISPLAY 0.617021 (-3150 2610);
PAINT PINK (-3150 2610);
FORCEPROP 1 LAST PATH I239
J 0
(-3150 2600);
DISPLAY 0.936170 (-3150 2600);
PAINT GREEN (-3150 2600);
DISPLAY INVISIBLE (-3150 2600);
FORCEPROP 1 LAST HDL_TAP TRUE
J 0
(-2825 2475);
DISPLAY 1.234043 (-2825 2475);
PAINT GREEN (-2825 2475);
DISPLAY INVISIBLE (-2825 2475);
FORCEPROP 1 LAST BODY_TYPE PLUMBING
J 0
(-3150 2550);
DISPLAY 1.234043 (-3150 2550);
PAINT GREEN (-3150 2550);
DISPLAY INVISIBLE (-3150 2550);
FORCEPROP 2 LAST CDS_LIB mstr_standard
J 0
(-3150 2600);
DISPLAY 0.787234 (-3150 2600);
PAINT MONO (-3150 2600);
DISPLAY INVISIBLE (-3150 2600);
FORCEADD TAP..6
(-3150 4300);
FORCEPROP 3 LASTPIN (-3100 4300) SIG_NAME M_A_MA<15>
J 0
(-3090 4310);
DISPLAY 0.659574 (-3090 4310);
PAINT MONO (-3090 4310);
DISPLAY INVISIBLE (-3090 4310);
FORCEPROP 1 LASTPIN (-3100 4300) BN 15
J 0
(-3150 4310);
DISPLAY 0.617021 (-3150 4310);
PAINT PINK (-3150 4310);
FORCEPROP 1 LAST PATH I24
J 0
(-3150 4300);
DISPLAY 0.936170 (-3150 4300);
PAINT GREEN (-3150 4300);
DISPLAY INVISIBLE (-3150 4300);
FORCEPROP 1 LAST HDL_TAP TRUE
J 0
(-2825 4175);
DISPLAY 1.234043 (-2825 4175);
PAINT GREEN (-2825 4175);
DISPLAY INVISIBLE (-2825 4175);
FORCEPROP 1 LAST BODY_TYPE PLUMBING
J 0
(-3150 4250);
DISPLAY 1.234043 (-3150 4250);
PAINT GREEN (-3150 4250);
DISPLAY INVISIBLE (-3150 4250);
FORCEPROP 2 LAST CDS_LIB mstr_standard
J 2
(-3150 4300);
DISPLAY 0.787234 (-3150 4300);
PAINT MONO (-3150 4300);
DISPLAY INVISIBLE (-3150 4300);
FORCEADD OFFPAGE..1
(-3800 2700);
FORCEPROP 2 LAST $XR1 44 
J 0
(-4111 2700);
DISPLAY 0.638298 (-4111 2700);
PAINT MONO (-4111 2700);
FORCEPROP 2 LAST $XR0 23 
J 0
(-4021 2700);
DISPLAY 0.638298 (-4021 2700);
PAINT MONO (-4021 2700);
FORCEPROP 2 LAST PATH I240
J 0
(-3750 2775);
DISPLAY 0.787234 (-3750 2775);
PAINT MONO (-3750 2775);
DISPLAY INVISIBLE (-3750 2775);
FORCEPROP 1 LAST COMMENT_BODY TRUE
J 0
(-3675 2600);
DISPLAY 0.936170 (-3675 2600);
PAINT GREEN (-3675 2600);
DISPLAY INVISIBLE (-3675 2600);
FORCEPROP 1 LAST OFFPAGE TRUE
J 0
(-3475 2575);
DISPLAY 0.936170 (-3475 2575);
PAINT GREEN (-3475 2575);
DISPLAY INVISIBLE (-3475 2575);
FORCEPROP 2 LAST CDS_LIB mstr_standard
J 0
(-3800 2700);
DISPLAY 0.787234 (-3800 2700);
PAINT MONO (-3800 2700);
DISPLAY INVISIBLE (-3800 2700);
FORCEADD TAP..6
(-3150 2900);
FORCEPROP 3 LASTPIN (-3100 2900) SIG_NAME M_A_CS_N<3>
J 0
(-3090 2910);
DISPLAY 0.659574 (-3090 2910);
PAINT MONO (-3090 2910);
DISPLAY INVISIBLE (-3090 2910);
FORCEPROP 1 LASTPIN (-3100 2900) BN 3
J 0
(-3150 2910);
DISPLAY 0.617021 (-3150 2910);
PAINT PINK (-3150 2910);
FORCEPROP 1 LAST PATH I241
J 0
(-3150 2900);
DISPLAY 0.936170 (-3150 2900);
PAINT GREEN (-3150 2900);
DISPLAY INVISIBLE (-3150 2900);
FORCEPROP 1 LAST HDL_TAP TRUE
J 0
(-2825 2775);
DISPLAY 1.234043 (-2825 2775);
PAINT GREEN (-2825 2775);
DISPLAY INVISIBLE (-2825 2775);
FORCEPROP 1 LAST BODY_TYPE PLUMBING
J 0
(-3150 2850);
DISPLAY 1.234043 (-3150 2850);
PAINT GREEN (-3150 2850);
DISPLAY INVISIBLE (-3150 2850);
FORCEPROP 2 LAST CDS_LIB mstr_standard
J 0
(-3150 2900);
DISPLAY 0.787234 (-3150 2900);
PAINT MONO (-3150 2900);
DISPLAY INVISIBLE (-3150 2900);
FORCEADD TAP..6
(-3150 2850);
FORCEPROP 3 LASTPIN (-3100 2850) SIG_NAME M_A_CS_N<2>
J 0
(-3090 2860);
DISPLAY 0.659574 (-3090 2860);
PAINT MONO (-3090 2860);
DISPLAY INVISIBLE (-3090 2860);
FORCEPROP 1 LASTPIN (-3100 2850) BN 2
J 0
(-3150 2860);
DISPLAY 0.617021 (-3150 2860);
PAINT PINK (-3150 2860);
FORCEPROP 1 LAST PATH I242
J 0
(-3150 2850);
DISPLAY 0.936170 (-3150 2850);
PAINT GREEN (-3150 2850);
DISPLAY INVISIBLE (-3150 2850);
FORCEPROP 1 LAST HDL_TAP TRUE
J 0
(-2825 2725);
DISPLAY 1.234043 (-2825 2725);
PAINT GREEN (-2825 2725);
DISPLAY INVISIBLE (-2825 2725);
FORCEPROP 1 LAST BODY_TYPE PLUMBING
J 0
(-3150 2800);
DISPLAY 1.234043 (-3150 2800);
PAINT GREEN (-3150 2800);
DISPLAY INVISIBLE (-3150 2800);
FORCEPROP 2 LAST CDS_LIB mstr_standard
J 0
(-3150 2850);
DISPLAY 0.787234 (-3150 2850);
PAINT MONO (-3150 2850);
DISPLAY INVISIBLE (-3150 2850);
FORCEADD TAP..6
(-3150 2800);
FORCEPROP 3 LASTPIN (-3100 2800) SIG_NAME M_A_CS_N<1>
J 0
(-3090 2810);
DISPLAY 0.659574 (-3090 2810);
PAINT MONO (-3090 2810);
DISPLAY INVISIBLE (-3090 2810);
FORCEPROP 1 LASTPIN (-3100 2800) BN 1
J 0
(-3150 2810);
DISPLAY 0.617021 (-3150 2810);
PAINT PINK (-3150 2810);
FORCEPROP 1 LAST PATH I243
J 0
(-3150 2800);
DISPLAY 0.936170 (-3150 2800);
PAINT GREEN (-3150 2800);
DISPLAY INVISIBLE (-3150 2800);
FORCEPROP 1 LAST HDL_TAP TRUE
J 0
(-2825 2675);
DISPLAY 1.234043 (-2825 2675);
PAINT GREEN (-2825 2675);
DISPLAY INVISIBLE (-2825 2675);
FORCEPROP 1 LAST BODY_TYPE PLUMBING
J 0
(-3150 2750);
DISPLAY 1.234043 (-3150 2750);
PAINT GREEN (-3150 2750);
DISPLAY INVISIBLE (-3150 2750);
FORCEPROP 2 LAST CDS_LIB mstr_standard
J 0
(-3150 2800);
DISPLAY 0.787234 (-3150 2800);
PAINT MONO (-3150 2800);
DISPLAY INVISIBLE (-3150 2800);
FORCEADD TAP..6
(-3150 2750);
FORCEPROP 3 LASTPIN (-3100 2750) SIG_NAME M_A_CS_N<0>
J 0
(-3090 2760);
DISPLAY 0.659574 (-3090 2760);
PAINT MONO (-3090 2760);
DISPLAY INVISIBLE (-3090 2760);
FORCEPROP 1 LASTPIN (-3100 2750) BN 0
J 0
(-3150 2760);
DISPLAY 0.617021 (-3150 2760);
PAINT PINK (-3150 2760);
FORCEPROP 1 LAST PATH I244
J 0
(-3150 2750);
DISPLAY 0.936170 (-3150 2750);
PAINT GREEN (-3150 2750);
DISPLAY INVISIBLE (-3150 2750);
FORCEPROP 1 LAST HDL_TAP TRUE
J 0
(-2825 2625);
DISPLAY 1.234043 (-2825 2625);
PAINT GREEN (-2825 2625);
DISPLAY INVISIBLE (-2825 2625);
FORCEPROP 1 LAST BODY_TYPE PLUMBING
J 0
(-3150 2700);
DISPLAY 1.234043 (-3150 2700);
PAINT GREEN (-3150 2700);
DISPLAY INVISIBLE (-3150 2700);
FORCEPROP 2 LAST CDS_LIB mstr_standard
J 0
(-3150 2750);
DISPLAY 0.787234 (-3150 2750);
PAINT MONO (-3150 2750);
DISPLAY INVISIBLE (-3150 2750);
FORCEADD OFFPAGE..1
(-3800 2950);
FORCEPROP 2 LAST $XR1 44 
J 0
(-4111 2950);
DISPLAY 0.638298 (-4111 2950);
PAINT MONO (-4111 2950);
FORCEPROP 2 LAST $XR0 23 
J 0
(-4021 2950);
DISPLAY 0.638298 (-4021 2950);
PAINT MONO (-4021 2950);
FORCEPROP 2 LAST PATH I245
J 0
(-3750 3025);
DISPLAY 0.787234 (-3750 3025);
PAINT MONO (-3750 3025);
DISPLAY INVISIBLE (-3750 3025);
FORCEPROP 1 LAST COMMENT_BODY TRUE
J 0
(-3675 2850);
DISPLAY 0.936170 (-3675 2850);
PAINT GREEN (-3675 2850);
DISPLAY INVISIBLE (-3675 2850);
FORCEPROP 1 LAST OFFPAGE TRUE
J 0
(-3475 2825);
DISPLAY 0.936170 (-3475 2825);
PAINT GREEN (-3475 2825);
DISPLAY INVISIBLE (-3475 2825);
FORCEPROP 2 LAST CDS_LIB mstr_standard
J 0
(-3800 2950);
DISPLAY 0.787234 (-3800 2950);
PAINT MONO (-3800 2950);
DISPLAY INVISIBLE (-3800 2950);
FORCEADD TAP..6
(-3350 3050);
FORCEPROP 3 LASTPIN (-3300 3050) SIG_NAME M_A_CLK_DN<0>
J 0
(-3290 3060);
DISPLAY 0.659574 (-3290 3060);
PAINT MONO (-3290 3060);
DISPLAY INVISIBLE (-3290 3060);
FORCEPROP 1 LASTPIN (-3300 3050) BN 0
J 0
(-3350 3060);
DISPLAY 0.617021 (-3350 3060);
PAINT PINK (-3350 3060);
FORCEPROP 1 LAST PATH I247
J 0
(-3350 3050);
DISPLAY 0.936170 (-3350 3050);
PAINT GREEN (-3350 3050);
DISPLAY INVISIBLE (-3350 3050);
FORCEPROP 1 LAST HDL_TAP TRUE
J 0
(-3025 2925);
DISPLAY 1.234043 (-3025 2925);
PAINT GREEN (-3025 2925);
DISPLAY INVISIBLE (-3025 2925);
FORCEPROP 1 LAST BODY_TYPE PLUMBING
J 0
(-3350 3000);
DISPLAY 1.234043 (-3350 3000);
PAINT GREEN (-3350 3000);
DISPLAY INVISIBLE (-3350 3000);
FORCEPROP 2 LAST CDS_LIB mstr_standard
J 0
(-3350 3050);
DISPLAY 0.787234 (-3350 3050);
PAINT MONO (-3350 3050);
DISPLAY INVISIBLE (-3350 3050);
FORCEADD TAP..6
(-3150 4250);
FORCEPROP 3 LASTPIN (-3100 4250) SIG_NAME M_A_MA<14>
J 0
(-3090 4260);
DISPLAY 0.659574 (-3090 4260);
PAINT MONO (-3090 4260);
DISPLAY INVISIBLE (-3090 4260);
FORCEPROP 1 LASTPIN (-3100 4250) BN 14
J 0
(-3150 4260);
DISPLAY 0.617021 (-3150 4260);
PAINT PINK (-3150 4260);
FORCEPROP 1 LAST PATH I25
J 0
(-3150 4250);
DISPLAY 0.936170 (-3150 4250);
PAINT GREEN (-3150 4250);
DISPLAY INVISIBLE (-3150 4250);
FORCEPROP 1 LAST HDL_TAP TRUE
J 0
(-2825 4125);
DISPLAY 1.234043 (-2825 4125);
PAINT GREEN (-2825 4125);
DISPLAY INVISIBLE (-2825 4125);
FORCEPROP 1 LAST BODY_TYPE PLUMBING
J 0
(-3150 4200);
DISPLAY 1.234043 (-3150 4200);
PAINT GREEN (-3150 4200);
DISPLAY INVISIBLE (-3150 4200);
FORCEPROP 2 LAST CDS_LIB mstr_standard
J 2
(-3150 4250);
DISPLAY 0.787234 (-3150 4250);
PAINT MONO (-3150 4250);
DISPLAY INVISIBLE (-3150 4250);
FORCEADD TAP..6
(-3150 3200);
FORCEPROP 3 LASTPIN (-3100 3200) SIG_NAME M_A_CLK_DP<1>
J 0
(-3090 3210);
DISPLAY 0.659574 (-3090 3210);
PAINT MONO (-3090 3210);
DISPLAY INVISIBLE (-3090 3210);
FORCEPROP 1 LASTPIN (-3100 3200) BN 1
J 0
(-3150 3210);
DISPLAY 0.617021 (-3150 3210);
PAINT PINK (-3150 3210);
FORCEPROP 1 LAST PATH I250
J 0
(-3150 3200);
DISPLAY 0.936170 (-3150 3200);
PAINT GREEN (-3150 3200);
DISPLAY INVISIBLE (-3150 3200);
FORCEPROP 1 LAST HDL_TAP TRUE
J 0
(-2825 3075);
DISPLAY 1.234043 (-2825 3075);
PAINT GREEN (-2825 3075);
DISPLAY INVISIBLE (-2825 3075);
FORCEPROP 1 LAST BODY_TYPE PLUMBING
J 0
(-3150 3150);
DISPLAY 1.234043 (-3150 3150);
PAINT GREEN (-3150 3150);
DISPLAY INVISIBLE (-3150 3150);
FORCEPROP 2 LAST CDS_LIB mstr_standard
J 0
(-3150 3200);
DISPLAY 0.787234 (-3150 3200);
PAINT MONO (-3150 3200);
DISPLAY INVISIBLE (-3150 3200);
FORCEADD TAP..6
(-3150 3100);
FORCEPROP 3 LASTPIN (-3100 3100) SIG_NAME M_A_CLK_DP<0>
J 0
(-3090 3110);
DISPLAY 0.659574 (-3090 3110);
PAINT MONO (-3090 3110);
DISPLAY INVISIBLE (-3090 3110);
FORCEPROP 1 LASTPIN (-3100 3100) BN 0
J 0
(-3150 3110);
DISPLAY 0.617021 (-3150 3110);
PAINT PINK (-3150 3110);
FORCEPROP 1 LAST PATH I252
J 0
(-3150 3100);
DISPLAY 0.936170 (-3150 3100);
PAINT GREEN (-3150 3100);
DISPLAY INVISIBLE (-3150 3100);
FORCEPROP 1 LAST HDL_TAP TRUE
J 0
(-2825 2975);
DISPLAY 1.234043 (-2825 2975);
PAINT GREEN (-2825 2975);
DISPLAY INVISIBLE (-2825 2975);
FORCEPROP 1 LAST BODY_TYPE PLUMBING
J 0
(-3150 3050);
DISPLAY 1.234043 (-3150 3050);
PAINT GREEN (-3150 3050);
DISPLAY INVISIBLE (-3150 3050);
FORCEPROP 2 LAST CDS_LIB mstr_standard
J 0
(-3150 3100);
DISPLAY 0.787234 (-3150 3100);
PAINT MONO (-3150 3100);
DISPLAY INVISIBLE (-3150 3100);
FORCEADD TAP..6
(-3350 3150);
FORCEPROP 3 LASTPIN (-3300 3150) SIG_NAME M_A_CLK_DN<1>
J 0
(-3290 3160);
DISPLAY 0.659574 (-3290 3160);
PAINT MONO (-3290 3160);
DISPLAY INVISIBLE (-3290 3160);
FORCEPROP 1 LASTPIN (-3300 3150) BN 1
J 0
(-3350 3160);
DISPLAY 0.617021 (-3350 3160);
PAINT PINK (-3350 3160);
FORCEPROP 1 LAST PATH I254
J 0
(-3350 3150);
DISPLAY 0.936170 (-3350 3150);
PAINT GREEN (-3350 3150);
DISPLAY INVISIBLE (-3350 3150);
FORCEPROP 1 LAST HDL_TAP TRUE
J 0
(-3025 3025);
DISPLAY 1.234043 (-3025 3025);
PAINT GREEN (-3025 3025);
DISPLAY INVISIBLE (-3025 3025);
FORCEPROP 1 LAST BODY_TYPE PLUMBING
J 0
(-3350 3100);
DISPLAY 1.234043 (-3350 3100);
PAINT GREEN (-3350 3100);
DISPLAY INVISIBLE (-3350 3100);
FORCEPROP 2 LAST CDS_LIB mstr_standard
J 0
(-3350 3150);
DISPLAY 0.787234 (-3350 3150);
PAINT MONO (-3350 3150);
DISPLAY INVISIBLE (-3350 3150);
FORCEADD OFFPAGE..1
(-3800 3250);
FORCEPROP 2 LAST $XR1 44 
J 0
(-4111 3250);
DISPLAY 0.638298 (-4111 3250);
PAINT MONO (-4111 3250);
FORCEPROP 2 LAST $XR0 23 
J 0
(-4021 3250);
DISPLAY 0.638298 (-4021 3250);
PAINT MONO (-4021 3250);
FORCEPROP 2 LAST PATH I255
J 0
(-3750 3325);
DISPLAY 0.787234 (-3750 3325);
PAINT MONO (-3750 3325);
DISPLAY INVISIBLE (-3750 3325);
FORCEPROP 1 LAST COMMENT_BODY TRUE
J 0
(-3675 3150);
DISPLAY 0.936170 (-3675 3150);
PAINT GREEN (-3675 3150);
DISPLAY INVISIBLE (-3675 3150);
FORCEPROP 1 LAST OFFPAGE TRUE
J 0
(-3475 3125);
DISPLAY 0.936170 (-3475 3125);
PAINT GREEN (-3475 3125);
DISPLAY INVISIBLE (-3475 3125);
FORCEPROP 2 LAST CDS_LIB mstr_standard
J 0
(-3800 3250);
DISPLAY 0.787234 (-3800 3250);
PAINT MONO (-3800 3250);
DISPLAY INVISIBLE (-3800 3250);
FORCEADD OFFPAGE..1
(-3800 3200);
FORCEPROP 2 LAST $XR1 44 
J 0
(-4111 3200);
DISPLAY 0.638298 (-4111 3200);
PAINT MONO (-4111 3200);
FORCEPROP 2 LAST $XR0 23 
J 0
(-4021 3200);
DISPLAY 0.638298 (-4021 3200);
PAINT MONO (-4021 3200);
FORCEPROP 2 LAST PATH I256
J 0
(-3750 3275);
DISPLAY 0.787234 (-3750 3275);
PAINT MONO (-3750 3275);
DISPLAY INVISIBLE (-3750 3275);
FORCEPROP 1 LAST COMMENT_BODY TRUE
J 0
(-3675 3100);
DISPLAY 0.936170 (-3675 3100);
PAINT GREEN (-3675 3100);
DISPLAY INVISIBLE (-3675 3100);
FORCEPROP 1 LAST OFFPAGE TRUE
J 0
(-3475 3075);
DISPLAY 0.936170 (-3475 3075);
PAINT GREEN (-3475 3075);
DISPLAY INVISIBLE (-3475 3075);
FORCEPROP 2 LAST CDS_LIB mstr_standard
J 0
(-3800 3200);
DISPLAY 0.787234 (-3800 3200);
PAINT MONO (-3800 3200);
DISPLAY INVISIBLE (-3800 3200);
FORCEADD OFFPAGE..1
(-3800 1350);
FORCEPROP 2 LAST $XR5 48 
J 0
(-4501 1350);
DISPLAY 0.638298 (-4501 1350);
PAINT MONO (-4501 1350);
FORCEPROP 2 LAST $XR4 47 
J 0
(-4411 1350);
DISPLAY 0.638298 (-4411 1350);
PAINT MONO (-4411 1350);
FORCEPROP 2 LAST $XR3 46 
J 0
(-4321 1350);
DISPLAY 0.638298 (-4321 1350);
PAINT MONO (-4321 1350);
FORCEPROP 2 LAST $XR2 45 
J 0
(-4231 1350);
DISPLAY 0.638298 (-4231 1350);
PAINT MONO (-4231 1350);
FORCEPROP 2 LAST $XR1 44 
J 0
(-4141 1350);
DISPLAY 0.638298 (-4141 1350);
PAINT MONO (-4141 1350);
FORCEPROP 2 LAST $XR0 99 
J 0
(-4051 1350);
DISPLAY 0.638298 (-4051 1350);
PAINT MONO (-4051 1350);
FORCEPROP 2 LAST PATH I257
J 0
(-3750 1425);
DISPLAY 0.787234 (-3750 1425);
PAINT MONO (-3750 1425);
DISPLAY INVISIBLE (-3750 1425);
FORCEPROP 1 LAST COMMENT_BODY TRUE
J 0
(-3675 1250);
DISPLAY 0.936170 (-3675 1250);
PAINT GREEN (-3675 1250);
DISPLAY INVISIBLE (-3675 1250);
FORCEPROP 1 LAST OFFPAGE TRUE
J 0
(-3475 1225);
DISPLAY 0.936170 (-3475 1225);
PAINT GREEN (-3475 1225);
DISPLAY INVISIBLE (-3475 1225);
FORCEPROP 2 LAST CDS_LIB mstr_standard
J 0
(-3800 1350);
DISPLAY 0.787234 (-3800 1350);
PAINT MONO (-3800 1350);
DISPLAY INVISIBLE (-3800 1350);
FORCEADD OFFPAGE..6
(-3800 1400);
FORCEPROP 2 LASTPIN (-3750 1400) SIG_NAME SMB_DDR_ABC_VPP_SDA
J 0
(-3710 1410);
DISPLAY 0.617021 (-3710 1410);
PAINT ORANGE (-3710 1410);
FORCEPROP 2 LAST $XR5 99 
J 0
(-4499 1400);
DISPLAY 0.638298 (-4499 1400);
PAINT MONO (-4499 1400);
FORCEPROP 2 LAST $XR4 48 
J 0
(-4409 1400);
DISPLAY 0.638298 (-4409 1400);
PAINT MONO (-4409 1400);
FORCEPROP 2 LAST $XR3 47 
J 0
(-4319 1400);
DISPLAY 0.638298 (-4319 1400);
PAINT MONO (-4319 1400);
FORCEPROP 2 LAST $XR2 46 
J 0
(-4229 1400);
DISPLAY 0.638298 (-4229 1400);
PAINT MONO (-4229 1400);
FORCEPROP 2 LAST $XR1 45 
J 0
(-4139 1400);
DISPLAY 0.638298 (-4139 1400);
PAINT MONO (-4139 1400);
FORCEPROP 2 LAST $XR0 44 
J 0
(-4049 1400);
DISPLAY 0.638298 (-4049 1400);
PAINT MONO (-4049 1400);
FORCEPROP 2 LAST PATH I258
J 0
(-3750 1475);
DISPLAY 0.787234 (-3750 1475);
PAINT MONO (-3750 1475);
DISPLAY INVISIBLE (-3750 1475);
FORCEPROP 1 LAST COMMENT_BODY TRUE
J 0
(-3700 1325);
DISPLAY 0.936170 (-3700 1325);
PAINT GREEN (-3700 1325);
DISPLAY INVISIBLE (-3700 1325);
FORCEPROP 1 LAST OFFPAGE TRUE
J 0
(-3475 1275);
DISPLAY 0.936170 (-3475 1275);
PAINT GREEN (-3475 1275);
DISPLAY INVISIBLE (-3475 1275);
FORCEPROP 2 LAST CDS_LIB mstr_standard
J 0
(-3800 1400);
DISPLAY 0.787234 (-3800 1400);
PAINT MONO (-3800 1400);
DISPLAY INVISIBLE (-3800 1400);
FORCEADD SCONN288_H44441004..3
(1750 2450);
FORCEPROP 2 LASTPIN (1250 1700) $PN 120
J 2
(1240 1710);
DISPLAY 0.617021 (1240 1710);
PAINT ORANGE (1240 1710);
FORCEPROP 2 LASTPIN (2250 1300) $PN 283
J 0
(2260 1310);
DISPLAY 0.617021 (2260 1310);
PAINT ORANGE (2260 1310);
FORCEPROP 2 LASTPIN (2250 1350) $PN 281
J 0
(2260 1360);
DISPLAY 0.617021 (2260 1360);
PAINT ORANGE (2260 1360);
FORCEPROP 2 LASTPIN (2250 1400) $PN 279
J 0
(2260 1410);
DISPLAY 0.617021 (2260 1410);
PAINT ORANGE (2260 1410);
FORCEPROP 2 LASTPIN (2250 1450) $PN 276
J 0
(2260 1460);
DISPLAY 0.617021 (2260 1460);
PAINT ORANGE (2260 1460);
FORCEPROP 2 LASTPIN (2250 1500) $PN 274
J 0
(2260 1510);
DISPLAY 0.617021 (2260 1510);
PAINT ORANGE (2260 1510);
FORCEPROP 2 LASTPIN (2250 1550) $PN 272
J 0
(2260 1560);
DISPLAY 0.617021 (2260 1560);
PAINT ORANGE (2260 1560);
FORCEPROP 2 LASTPIN (2250 1600) $PN 270
J 0
(2260 1610);
DISPLAY 0.617021 (2260 1610);
PAINT ORANGE (2260 1610);
FORCEPROP 2 LASTPIN (2250 1650) $PN 268
J 0
(2260 1660);
DISPLAY 0.617021 (2260 1660);
PAINT ORANGE (2260 1660);
FORCEPROP 2 LASTPIN (2250 1700) $PN 265
J 0
(2260 1710);
DISPLAY 0.617021 (2260 1710);
PAINT ORANGE (2260 1710);
FORCEPROP 2 LASTPIN (2250 1750) $PN 263
J 0
(2260 1760);
DISPLAY 0.617021 (2260 1760);
PAINT ORANGE (2260 1760);
FORCEPROP 2 LASTPIN (2250 1800) $PN 261
J 0
(2260 1810);
DISPLAY 0.617021 (2260 1810);
PAINT ORANGE (2260 1810);
FORCEPROP 2 LASTPIN (2250 1850) $PN 259
J 0
(2260 1860);
DISPLAY 0.617021 (2260 1860);
PAINT ORANGE (2260 1860);
FORCEPROP 2 LASTPIN (2250 1900) $PN 257
J 0
(2260 1910);
DISPLAY 0.617021 (2260 1910);
PAINT ORANGE (2260 1910);
FORCEPROP 2 LASTPIN (2250 1950) $PN 254
J 0
(2260 1960);
DISPLAY 0.617021 (2260 1960);
PAINT ORANGE (2260 1960);
FORCEPROP 2 LASTPIN (2250 2000) $PN 252
J 0
(2260 2010);
DISPLAY 0.617021 (2260 2010);
PAINT ORANGE (2260 2010);
FORCEPROP 2 LASTPIN (2250 2050) $PN 250
J 0
(2260 2060);
DISPLAY 0.617021 (2260 2060);
PAINT ORANGE (2260 2060);
FORCEPROP 2 LASTPIN (2250 2100) $PN 248
J 0
(2260 2110);
DISPLAY 0.617021 (2260 2110);
PAINT ORANGE (2260 2110);
FORCEPROP 2 LASTPIN (2250 2150) $PN 246
J 0
(2260 2160);
DISPLAY 0.617021 (2260 2160);
PAINT ORANGE (2260 2160);
FORCEPROP 2 LASTPIN (2250 2200) $PN 243
J 0
(2260 2210);
DISPLAY 0.617021 (2260 2210);
PAINT ORANGE (2260 2210);
FORCEPROP 2 LASTPIN (2250 2250) $PN 241
J 0
(2260 2260);
DISPLAY 0.617021 (2260 2260);
PAINT ORANGE (2260 2260);
FORCEPROP 2 LASTPIN (2250 2300) $PN 239
J 0
(2260 2310);
DISPLAY 0.617021 (2260 2310);
PAINT ORANGE (2260 2310);
FORCEPROP 2 LASTPIN (2250 2350) $PN 202
J 0
(2260 2360);
DISPLAY 0.617021 (2260 2360);
PAINT ORANGE (2260 2360);
FORCEPROP 2 LASTPIN (2250 2400) $PN 200
J 0
(2260 2410);
DISPLAY 0.617021 (2260 2410);
PAINT ORANGE (2260 2410);
FORCEPROP 2 LASTPIN (2250 2450) $PN 198
J 0
(2260 2460);
DISPLAY 0.617021 (2260 2460);
PAINT ORANGE (2260 2460);
FORCEPROP 2 LASTPIN (2250 2500) $PN 195
J 0
(2260 2510);
DISPLAY 0.617021 (2260 2510);
PAINT ORANGE (2260 2510);
FORCEPROP 2 LASTPIN (2250 2550) $PN 193
J 0
(2260 2560);
DISPLAY 0.617021 (2260 2560);
PAINT ORANGE (2260 2560);
FORCEPROP 2 LASTPIN (2250 2600) $PN 191
J 0
(2260 2610);
DISPLAY 0.617021 (2260 2610);
PAINT ORANGE (2260 2610);
FORCEPROP 2 LASTPIN (2250 2650) $PN 189
J 0
(2260 2660);
DISPLAY 0.617021 (2260 2660);
PAINT ORANGE (2260 2660);
FORCEPROP 2 LASTPIN (2250 2700) $PN 187
J 0
(2260 2710);
DISPLAY 0.617021 (2260 2710);
PAINT ORANGE (2260 2710);
FORCEPROP 2 LASTPIN (2250 2750) $PN 184
J 0
(2260 2760);
DISPLAY 0.617021 (2260 2760);
PAINT ORANGE (2260 2760);
FORCEPROP 2 LASTPIN (2250 2800) $PN 182
J 0
(2260 2810);
DISPLAY 0.617021 (2260 2810);
PAINT ORANGE (2260 2810);
FORCEPROP 2 LASTPIN (2250 2850) $PN 180
J 0
(2260 2860);
DISPLAY 0.617021 (2260 2860);
PAINT ORANGE (2260 2860);
FORCEPROP 2 LASTPIN (2250 2900) $PN 178
J 0
(2260 2910);
DISPLAY 0.617021 (2260 2910);
PAINT ORANGE (2260 2910);
FORCEPROP 2 LASTPIN (2250 2950) $PN 176
J 0
(2260 2960);
DISPLAY 0.617021 (2260 2960);
PAINT ORANGE (2260 2960);
FORCEPROP 2 LASTPIN (2250 3000) $PN 173
J 0
(2260 3010);
DISPLAY 0.617021 (2260 3010);
PAINT ORANGE (2260 3010);
FORCEPROP 2 LASTPIN (2250 3050) $PN 171
J 0
(2260 3060);
DISPLAY 0.617021 (2260 3060);
PAINT ORANGE (2260 3060);
FORCEPROP 2 LASTPIN (2250 3100) $PN 169
J 0
(2260 3110);
DISPLAY 0.617021 (2260 3110);
PAINT ORANGE (2260 3110);
FORCEPROP 2 LASTPIN (2250 3150) $PN 167
J 0
(2260 3160);
DISPLAY 0.617021 (2260 3160);
PAINT ORANGE (2260 3160);
FORCEPROP 2 LASTPIN (2250 3200) $PN 165
J 0
(2260 3210);
DISPLAY 0.617021 (2260 3210);
PAINT ORANGE (2260 3210);
FORCEPROP 2 LASTPIN (2250 3250) $PN 162
J 0
(2260 3260);
DISPLAY 0.617021 (2260 3260);
PAINT ORANGE (2260 3260);
FORCEPROP 2 LASTPIN (2250 3300) $PN 160
J 0
(2260 3310);
DISPLAY 0.617021 (2260 3310);
PAINT ORANGE (2260 3310);
FORCEPROP 2 LASTPIN (2250 3350) $PN 158
J 0
(2260 3360);
DISPLAY 0.617021 (2260 3360);
PAINT ORANGE (2260 3360);
FORCEPROP 2 LASTPIN (2250 3400) $PN 156
J 0
(2260 3410);
DISPLAY 0.617021 (2260 3410);
PAINT ORANGE (2260 3410);
FORCEPROP 2 LASTPIN (2250 3450) $PN 154
J 0
(2260 3460);
DISPLAY 0.617021 (2260 3460);
PAINT ORANGE (2260 3460);
FORCEPROP 2 LASTPIN (2250 3500) $PN 151
J 0
(2260 3510);
DISPLAY 0.617021 (2260 3510);
PAINT ORANGE (2260 3510);
FORCEPROP 2 LASTPIN (2250 3550) $PN 149
J 0
(2260 3560);
DISPLAY 0.617021 (2260 3560);
PAINT ORANGE (2260 3560);
FORCEPROP 2 LASTPIN (2250 3600) $PN 147
J 0
(2260 3610);
DISPLAY 0.617021 (2260 3610);
PAINT ORANGE (2260 3610);
FORCEPROP 2 LASTPIN (1250 1300) $PN 138
J 2
(1240 1310);
DISPLAY 0.617021 (1240 1310);
PAINT ORANGE (1240 1310);
FORCEPROP 2 LASTPIN (1250 1350) $PN 136
J 2
(1240 1360);
DISPLAY 0.617021 (1240 1360);
PAINT ORANGE (1240 1360);
FORCEPROP 2 LASTPIN (1250 1400) $PN 134
J 2
(1240 1410);
DISPLAY 0.617021 (1240 1410);
PAINT ORANGE (1240 1410);
FORCEPROP 2 LASTPIN (1250 1450) $PN 131
J 2
(1240 1460);
DISPLAY 0.617021 (1240 1460);
PAINT ORANGE (1240 1460);
FORCEPROP 2 LASTPIN (1250 1500) $PN 129
J 2
(1240 1510);
DISPLAY 0.617021 (1240 1510);
PAINT ORANGE (1240 1510);
FORCEPROP 2 LASTPIN (1250 1550) $PN 127
J 2
(1240 1560);
DISPLAY 0.617021 (1240 1560);
PAINT ORANGE (1240 1560);
FORCEPROP 2 LASTPIN (1250 1650) $PN 123
J 2
(1240 1660);
DISPLAY 0.617021 (1240 1660);
PAINT ORANGE (1240 1660);
FORCEPROP 2 LASTPIN (1250 1750) $PN 118
J 2
(1240 1760);
DISPLAY 0.617021 (1240 1760);
PAINT ORANGE (1240 1760);
FORCEPROP 2 LASTPIN (1250 1800) $PN 116
J 2
(1240 1810);
DISPLAY 0.617021 (1240 1810);
PAINT ORANGE (1240 1810);
FORCEPROP 2 LASTPIN (1250 1850) $PN 114
J 2
(1240 1860);
DISPLAY 0.617021 (1240 1860);
PAINT ORANGE (1240 1860);
FORCEPROP 2 LASTPIN (1250 1900) $PN 112
J 2
(1240 1910);
DISPLAY 0.617021 (1240 1910);
PAINT ORANGE (1240 1910);
FORCEPROP 2 LASTPIN (1250 1950) $PN 109
J 2
(1240 1960);
DISPLAY 0.617021 (1240 1960);
PAINT ORANGE (1240 1960);
FORCEPROP 2 LASTPIN (1250 2000) $PN 107
J 2
(1240 2010);
DISPLAY 0.617021 (1240 2010);
PAINT ORANGE (1240 2010);
FORCEPROP 2 LASTPIN (1250 2050) $PN 105
J 2
(1240 2060);
DISPLAY 0.617021 (1240 2060);
PAINT ORANGE (1240 2060);
FORCEPROP 2 LASTPIN (1250 2100) $PN 103
J 2
(1240 2110);
DISPLAY 0.617021 (1240 2110);
PAINT ORANGE (1240 2110);
FORCEPROP 2 LASTPIN (1250 2150) $PN 101
J 2
(1240 2160);
DISPLAY 0.617021 (1240 2160);
PAINT ORANGE (1240 2160);
FORCEPROP 2 LASTPIN (1250 2200) $PN 98
J 2
(1240 2210);
DISPLAY 0.617021 (1240 2210);
PAINT ORANGE (1240 2210);
FORCEPROP 2 LASTPIN (1250 2250) $PN 96
J 2
(1240 2260);
DISPLAY 0.617021 (1240 2260);
PAINT ORANGE (1240 2260);
FORCEPROP 2 LASTPIN (1250 2300) $PN 94
J 2
(1240 2310);
DISPLAY 0.617021 (1240 2310);
PAINT ORANGE (1240 2310);
FORCEPROP 2 LASTPIN (1250 2350) $PN 57
J 2
(1240 2360);
DISPLAY 0.617021 (1240 2360);
PAINT ORANGE (1240 2360);
FORCEPROP 2 LASTPIN (1250 2400) $PN 55
J 2
(1240 2410);
DISPLAY 0.617021 (1240 2410);
PAINT ORANGE (1240 2410);
FORCEPROP 2 LASTPIN (1250 2450) $PN 53
J 2
(1240 2460);
DISPLAY 0.617021 (1240 2460);
PAINT ORANGE (1240 2460);
FORCEPROP 2 LASTPIN (1250 2500) $PN 50
J 2
(1240 2510);
DISPLAY 0.617021 (1240 2510);
PAINT ORANGE (1240 2510);
FORCEPROP 2 LASTPIN (1250 2550) $PN 48
J 2
(1240 2560);
DISPLAY 0.617021 (1240 2560);
PAINT ORANGE (1240 2560);
FORCEPROP 2 LASTPIN (1250 2600) $PN 46
J 2
(1240 2610);
DISPLAY 0.617021 (1240 2610);
PAINT ORANGE (1240 2610);
FORCEPROP 2 LASTPIN (1250 2650) $PN 44
J 2
(1240 2660);
DISPLAY 0.617021 (1240 2660);
PAINT ORANGE (1240 2660);
FORCEPROP 2 LASTPIN (1250 2700) $PN 42
J 2
(1240 2710);
DISPLAY 0.617021 (1240 2710);
PAINT ORANGE (1240 2710);
FORCEPROP 2 LASTPIN (1250 2750) $PN 39
J 2
(1240 2760);
DISPLAY 0.617021 (1240 2760);
PAINT ORANGE (1240 2760);
FORCEPROP 2 LASTPIN (1250 2800) $PN 37
J 2
(1240 2810);
DISPLAY 0.617021 (1240 2810);
PAINT ORANGE (1240 2810);
FORCEPROP 2 LASTPIN (1250 2850) $PN 35
J 2
(1240 2860);
DISPLAY 0.617021 (1240 2860);
PAINT ORANGE (1240 2860);
FORCEPROP 2 LASTPIN (1250 2900) $PN 33
J 2
(1240 2910);
DISPLAY 0.617021 (1240 2910);
PAINT ORANGE (1240 2910);
FORCEPROP 2 LASTPIN (1250 2950) $PN 31
J 2
(1240 2960);
DISPLAY 0.617021 (1240 2960);
PAINT ORANGE (1240 2960);
FORCEPROP 2 LASTPIN (1250 3000) $PN 28
J 2
(1240 3010);
DISPLAY 0.617021 (1240 3010);
PAINT ORANGE (1240 3010);
FORCEPROP 2 LASTPIN (1250 3050) $PN 26
J 2
(1240 3060);
DISPLAY 0.617021 (1240 3060);
PAINT ORANGE (1240 3060);
FORCEPROP 2 LASTPIN (1250 3100) $PN 24
J 2
(1240 3110);
DISPLAY 0.617021 (1240 3110);
PAINT ORANGE (1240 3110);
FORCEPROP 2 LASTPIN (1250 3150) $PN 22
J 2
(1240 3160);
DISPLAY 0.617021 (1240 3160);
PAINT ORANGE (1240 3160);
FORCEPROP 2 LASTPIN (1250 3200) $PN 20
J 2
(1240 3210);
DISPLAY 0.617021 (1240 3210);
PAINT ORANGE (1240 3210);
FORCEPROP 2 LASTPIN (1250 3250) $PN 17
J 2
(1240 3260);
DISPLAY 0.617021 (1240 3260);
PAINT ORANGE (1240 3260);
FORCEPROP 2 LASTPIN (1250 3300) $PN 15
J 2
(1240 3310);
DISPLAY 0.617021 (1240 3310);
PAINT ORANGE (1240 3310);
FORCEPROP 2 LASTPIN (1250 3350) $PN 13
J 2
(1240 3360);
DISPLAY 0.617021 (1240 3360);
PAINT ORANGE (1240 3360);
FORCEPROP 2 LASTPIN (1250 3400) $PN 11
J 2
(1240 3410);
DISPLAY 0.617021 (1240 3410);
PAINT ORANGE (1240 3410);
FORCEPROP 2 LASTPIN (1250 3450) $PN 9
J 2
(1240 3460);
DISPLAY 0.617021 (1240 3460);
PAINT ORANGE (1240 3460);
FORCEPROP 2 LASTPIN (1250 3500) $PN 6
J 2
(1240 3510);
DISPLAY 0.617021 (1240 3510);
PAINT ORANGE (1240 3510);
FORCEPROP 2 LASTPIN (1250 3550) $PN 4
J 2
(1240 3560);
DISPLAY 0.617021 (1240 3560);
PAINT ORANGE (1240 3560);
FORCEPROP 2 LASTPIN (1250 3600) $PN 2
J 2
(1240 3610);
DISPLAY 0.617021 (1240 3610);
PAINT ORANGE (1240 3610);
FORCEPROP 1 LAST MATERIAL SCONN
J 0
(1300 3800);
DISPLAY 0.617021 (1300 3800);
PAINT SKYBLUE (1300 3800);
FORCEPROP 1 LAST PART_NUMBER H44441-004
J 0
(1300 1100);
DISPLAY 0.617021 (1300 1100);
PAINT BLUE (1300 1100);
FORCEPROP 1 LAST LOCATION J4G1
J 0
(1300 3850);
DISPLAY 0.617021 (1300 3850);
PAINT AQUA (1300 3850);
FORCEPROP 2 LASTPIN (1250 1600) $PN 125
J 2
(1240 1610);
DISPLAY 0.617021 (1240 1610);
PAINT ORANGE (1240 1610);
FORCEPROP 2 LAST ROOM DDR4_CH_A
J 0
(1750 2450);
PAINT ORANGE (1750 2450);
DISPLAY INVISIBLE (1750 2450);
FORCEPROP 1 LAST PATH I259
J 0
(1750 3800);
PAINT GREEN (1750 3800);
DISPLAY INVISIBLE (1750 3800);
FORCEPROP 2 LAST CDS_LOCATION J4G1
J 0
(1300 3850);
DISPLAY 0.617021 (1300 3850);
PAINT AQUA (1300 3850);
DISPLAY INVISIBLE (1300 3850);
FORCEPROP 2 LAST SEC 3
J 0
(1300 3900);
DISPLAY 0.680851 (1300 3900);
PAINT MONO (1300 3900);
DISPLAY INVISIBLE (1300 3900);
FORCEPROP 2 LAST SEC_TYPE PIP
J 0
(1300 3900);
DISPLAY 1.021277 (1300 3900);
PAINT ORANGE (1300 3900);
DISPLAY INVISIBLE (1300 3900);
FORCEPROP 2 LAST CDS_LIB mstr_sconn
J 0
(1750 2450);
PAINT ORANGE (1750 2450);
DISPLAY INVISIBLE (1750 2450);
FORCEPROP 2 LAST BOM_COST MEM
J 0
(1750 2450);
PAINT ORANGE (1750 2450);
DISPLAY INVISIBLE (1750 2450);
FORCEPROP 1 LAST PACK_TYPE PIP
J 0
(1300 3900);
PAINT SKYBLUE (1300 3900);
DISPLAY INVISIBLE (1300 3900);
FORCEADD TAP..6
(-3150 4200);
FORCEPROP 3 LASTPIN (-3100 4200) SIG_NAME M_A_MA<13>
J 0
(-3090 4210);
DISPLAY 0.659574 (-3090 4210);
PAINT MONO (-3090 4210);
DISPLAY INVISIBLE (-3090 4210);
FORCEPROP 1 LASTPIN (-3100 4200) BN 13
J 0
(-3150 4210);
DISPLAY 0.617021 (-3150 4210);
PAINT PINK (-3150 4210);
FORCEPROP 1 LAST PATH I26
J 0
(-3150 4200);
DISPLAY 0.936170 (-3150 4200);
PAINT GREEN (-3150 4200);
DISPLAY INVISIBLE (-3150 4200);
FORCEPROP 1 LAST HDL_TAP TRUE
J 0
(-2825 4075);
DISPLAY 1.234043 (-2825 4075);
PAINT GREEN (-2825 4075);
DISPLAY INVISIBLE (-2825 4075);
FORCEPROP 1 LAST BODY_TYPE PLUMBING
J 0
(-3150 4150);
DISPLAY 1.234043 (-3150 4150);
PAINT GREEN (-3150 4150);
DISPLAY INVISIBLE (-3150 4150);
FORCEPROP 2 LAST CDS_LIB mstr_standard
J 2
(-3150 4200);
DISPLAY 0.787234 (-3150 4200);
PAINT MONO (-3150 4200);
DISPLAY INVISIBLE (-3150 4200);
FORCEADD SCONN288_H44441004..4
(-100 1700);
FORCEPROP 2 LASTPIN (400 2500) $PN 145
J 0
(410 2510);
DISPLAY 0.617021 (410 2510);
PAINT ORANGE (410 2510);
FORCEPROP 2 LASTPIN (400 2550) $PN 1
J 0
(410 2560);
DISPLAY 0.617021 (410 2560);
PAINT ORANGE (410 2560);
FORCEPROP 2 LASTPIN (-600 850) $PN 236
J 2
(-610 860);
DISPLAY 0.617021 (-610 860);
PAINT ORANGE (-610 860);
FORCEPROP 2 LASTPIN (-600 900) $PN 233
J 2
(-610 910);
DISPLAY 0.617021 (-610 910);
PAINT ORANGE (-610 910);
FORCEPROP 2 LASTPIN (-600 950) $PN 231
J 2
(-610 960);
DISPLAY 0.617021 (-610 960);
PAINT ORANGE (-610 960);
FORCEPROP 2 LASTPIN (-600 1000) $PN 229
J 2
(-610 1010);
DISPLAY 0.617021 (-610 1010);
PAINT ORANGE (-610 1010);
FORCEPROP 2 LASTPIN (-600 1050) $PN 226
J 2
(-610 1060);
DISPLAY 0.617021 (-610 1060);
PAINT ORANGE (-610 1060);
FORCEPROP 2 LASTPIN (-600 1100) $PN 223
J 2
(-610 1110);
DISPLAY 0.617021 (-610 1110);
PAINT ORANGE (-610 1110);
FORCEPROP 2 LASTPIN (-600 1150) $PN 220
J 2
(-610 1160);
DISPLAY 0.617021 (-610 1160);
PAINT ORANGE (-610 1160);
FORCEPROP 2 LASTPIN (-600 1200) $PN 217
J 2
(-610 1210);
DISPLAY 0.617021 (-610 1210);
PAINT ORANGE (-610 1210);
FORCEPROP 2 LASTPIN (-600 1250) $PN 215
J 2
(-610 1260);
DISPLAY 0.617021 (-610 1260);
PAINT ORANGE (-610 1260);
FORCEPROP 2 LASTPIN (-600 1300) $PN 212
J 2
(-610 1310);
DISPLAY 0.617021 (-610 1310);
PAINT ORANGE (-610 1310);
FORCEPROP 2 LASTPIN (-600 1350) $PN 209
J 2
(-610 1360);
DISPLAY 0.617021 (-610 1360);
PAINT ORANGE (-610 1360);
FORCEPROP 2 LASTPIN (-600 1400) $PN 206
J 2
(-610 1410);
DISPLAY 0.617021 (-610 1410);
PAINT ORANGE (-610 1410);
FORCEPROP 2 LASTPIN (-600 1450) $PN 204
J 2
(-610 1460);
DISPLAY 0.617021 (-610 1460);
PAINT ORANGE (-610 1460);
FORCEPROP 2 LASTPIN (-600 1500) $PN 92
J 2
(-610 1510);
DISPLAY 0.617021 (-610 1510);
PAINT ORANGE (-610 1510);
FORCEPROP 2 LASTPIN (-600 1550) $PN 90
J 2
(-610 1560);
DISPLAY 0.617021 (-610 1560);
PAINT ORANGE (-610 1560);
FORCEPROP 2 LASTPIN (-600 1600) $PN 88
J 2
(-610 1610);
DISPLAY 0.617021 (-610 1610);
PAINT ORANGE (-610 1610);
FORCEPROP 2 LASTPIN (-600 1650) $PN 85
J 2
(-610 1660);
DISPLAY 0.617021 (-610 1660);
PAINT ORANGE (-610 1660);
FORCEPROP 2 LASTPIN (-600 1700) $PN 83
J 2
(-610 1710);
DISPLAY 0.617021 (-610 1710);
PAINT ORANGE (-610 1710);
FORCEPROP 2 LASTPIN (-600 1750) $PN 80
J 2
(-610 1760);
DISPLAY 0.617021 (-610 1760);
PAINT ORANGE (-610 1760);
FORCEPROP 2 LASTPIN (-600 1800) $PN 76
J 2
(-610 1810);
DISPLAY 0.617021 (-610 1810);
PAINT ORANGE (-610 1810);
FORCEPROP 2 LASTPIN (-600 1850) $PN 73
J 2
(-610 1860);
DISPLAY 0.617021 (-610 1860);
PAINT ORANGE (-610 1860);
FORCEPROP 2 LASTPIN (-600 1900) $PN 70
J 2
(-610 1910);
DISPLAY 0.617021 (-610 1910);
PAINT ORANGE (-610 1910);
FORCEPROP 2 LASTPIN (-600 1950) $PN 67
J 2
(-610 1960);
DISPLAY 0.617021 (-610 1960);
PAINT ORANGE (-610 1960);
FORCEPROP 2 LASTPIN (-600 2000) $PN 64
J 2
(-610 2010);
DISPLAY 0.617021 (-610 2010);
PAINT ORANGE (-610 2010);
FORCEPROP 2 LASTPIN (-600 2050) $PN 61
J 2
(-610 2060);
DISPLAY 0.617021 (-610 2060);
PAINT ORANGE (-610 2060);
FORCEPROP 2 LASTPIN (-600 2100) $PN 59
J 2
(-610 2110);
DISPLAY 0.617021 (-610 2110);
PAINT ORANGE (-610 2110);
FORCEPROP 2 LASTPIN (-600 2350) $PN 287
J 2
(-610 2360);
DISPLAY 0.617021 (-610 2360);
PAINT ORANGE (-610 2360);
FORCEPROP 2 LASTPIN (-600 2400) $PN 286
J 2
(-610 2410);
DISPLAY 0.617021 (-610 2410);
PAINT ORANGE (-610 2410);
FORCEPROP 2 LASTPIN (-600 2450) $PN 288
J 2
(-610 2460);
DISPLAY 0.617021 (-610 2460);
PAINT ORANGE (-610 2460);
FORCEPROP 2 LASTPIN (-600 2500) $PN 143
J 2
(-610 2510);
DISPLAY 0.617021 (-610 2510);
PAINT ORANGE (-610 2510);
FORCEPROP 2 LASTPIN (-600 2550) $PN 142
J 2
(-610 2560);
DISPLAY 0.617021 (-610 2560);
PAINT ORANGE (-610 2560);
FORCEPROP 2 LASTPIN (-600 2200) $PN 221
J 2
(-610 2210);
DISPLAY 0.617021 (-610 2210);
PAINT ORANGE (-610 2210);
FORCEPROP 2 LASTPIN (-600 2250) $PN 77
J 2
(-610 2260);
DISPLAY 0.617021 (-610 2260);
PAINT ORANGE (-610 2260);
FORCEPROP 1 LAST MATERIAL SCONN
J 0
(-550 2750);
DISPLAY 0.617021 (-550 2750);
PAINT SKYBLUE (-550 2750);
FORCEPROP 1 LAST PART_NUMBER H44441-004
J 0
(-550 650);
DISPLAY 0.617021 (-550 650);
PAINT BLUE (-550 650);
FORCEPROP 1 LAST LOCATION J4G1
J 0
(-550 2800);
DISPLAY 0.617021 (-550 2800);
PAINT AQUA (-550 2800);
FORCEPROP 2 LAST ROOM DDR4_CH_A
J 0
(-100 1700);
PAINT ORANGE (-100 1700);
DISPLAY INVISIBLE (-100 1700);
FORCEPROP 1 LAST PATH I260
J 0
(-100 2750);
PAINT GREEN (-100 2750);
DISPLAY INVISIBLE (-100 2750);
FORCEPROP 2 LAST CDS_LOCATION J4G1
J 0
(-550 2800);
DISPLAY 0.617021 (-550 2800);
PAINT AQUA (-550 2800);
DISPLAY INVISIBLE (-550 2800);
FORCEPROP 2 LAST SEC 4
J 0
(-550 2850);
DISPLAY 0.680851 (-550 2850);
PAINT MONO (-550 2850);
DISPLAY INVISIBLE (-550 2850);
FORCEPROP 2 LAST SEC_TYPE PIP
J 0
(-550 2850);
DISPLAY 1.021277 (-550 2850);
PAINT ORANGE (-550 2850);
DISPLAY INVISIBLE (-550 2850);
FORCEPROP 2 LAST CDS_LIB mstr_sconn
J 0
(-100 1700);
PAINT ORANGE (-100 1700);
DISPLAY INVISIBLE (-100 1700);
FORCEPROP 2 LAST BOM_COST MEM
J 0
(-100 1700);
PAINT ORANGE (-100 1700);
DISPLAY INVISIBLE (-100 1700);
FORCEPROP 1 LAST PACK_TYPE PIP
J 0
(-550 2850);
PAINT SKYBLUE (-550 2850);
DISPLAY INVISIBLE (-550 2850);
FORCEADD PVDDQ_ABC..1
(-1125 2250);
FORCEPROP 3 LASTPIN (-1125 2200) SIG_NAME PVDDQ_ABC\g
J 0
(-1115 2210);
DISPLAY 0.659574 (-1115 2210);
PAINT MONO (-1115 2210);
DISPLAY INVISIBLE (-1115 2210);
FORCEPROP 1 LAST HDL_POWER PVDDQ_ABC
J 1
(-1125 2300);
DISPLAY 0.872340 (-1125 2300);
PAINT GREEN (-1125 2300);
DISPLAY INVISIBLE (-1125 2300);
FORCEPROP 2 LAST ROOM DDR4_CH_A
J 0
(-1125 2350);
DISPLAY 0.787234 (-1125 2350);
PAINT ORANGE (-1125 2350);
DISPLAY INVISIBLE (-1125 2350);
FORCEPROP 1 LAST PATH I263
J 0
(-1075 2275);
DISPLAY 0.872340 (-1075 2275);
PAINT AQUA (-1075 2275);
DISPLAY INVISIBLE (-1075 2275);
FORCEPROP 1 LAST BODY_TYPE PLUMBING
J 0
(-1170 2207);
DISPLAY 0.340426 (-1170 2207);
PAINT GREEN (-1170 2207);
DISPLAY INVISIBLE (-1170 2207);
FORCEPROP 2 LAST CDS_LIB mstr_symbols
J 0
(-1125 2250);
PAINT ORANGE (-1125 2250);
DISPLAY INVISIBLE (-1125 2250);
FORCEPROP 2 LAST BOM_COST MEM
J 0
(-1125 2255);
PAINT ORANGE (-1125 2255);
DISPLAY INVISIBLE (-1125 2255);
FORCEPROP 1 LAST VOLTAGE 1.2V
J 0
(-1170 2207);
DISPLAY 0.340426 (-1170 2207);
PAINT SKYBLUE (-1170 2207);
DISPLAY INVISIBLE (-1170 2207);
FORCEADD GND..1
R 2
(1050 1150);
FORCEPROP 3 LASTPIN (1050 1200) SIG_NAME GND\g
J 0
(1060 1210);
DISPLAY 0.659574 (1060 1210);
PAINT MONO (1060 1210);
DISPLAY INVISIBLE (1060 1210);
FORCEPROP 1 LAST HDL_POWER GND
J 2
(1050 1300);
DISPLAY 0.553191 (1050 1300);
PAINT GREEN (1050 1300);
DISPLAY INVISIBLE (1050 1300);
FORCEPROP 2 LAST ROOM DDR4_CH_A
J 0
(1050 1155);
PAINT ORANGE (1050 1155);
DISPLAY INVISIBLE (1050 1155);
FORCEPROP 1 LAST PATH I264
J 2
(975 1150);
DISPLAY 1.404255 (975 1150);
PAINT GREEN (975 1150);
DISPLAY INVISIBLE (975 1150);
FORCEPROP 1 LAST BODY_TYPE PLUMBING
J 2
(1095 1107);
DISPLAY 0.340426 (1095 1107);
PAINT GREEN (1095 1107);
DISPLAY INVISIBLE (1095 1107);
FORCEPROP 2 LAST BOM_COST MEM
J 0
(1050 1155);
PAINT ORANGE (1050 1155);
DISPLAY INVISIBLE (1050 1155);
FORCEPROP 2 LAST CDS_LIB mstr_symbols
J 0
(1050 1150);
DISPLAY 0.787234 (1050 1150);
PAINT MONO (1050 1150);
DISPLAY INVISIBLE (1050 1150);
FORCEPROP 1 LAST SIZE 1B
J 2
(975 1100);
DISPLAY 1.170213 (975 1100);
PAINT GREEN (975 1100);
DISPLAY INVISIBLE (975 1100);
FORCEPROP 1 LAST VOLTAGE 0
J 0
(1050 1150);
PAINT SKYBLUE (1050 1150);
DISPLAY INVISIBLE (1050 1150);
FORCEADD GND..1
R 2
(2450 1150);
FORCEPROP 3 LASTPIN (2450 1200) SIG_NAME GND\g
J 0
(2460 1210);
DISPLAY 0.659574 (2460 1210);
PAINT MONO (2460 1210);
DISPLAY INVISIBLE (2460 1210);
FORCEPROP 1 LAST HDL_POWER GND
J 2
(2450 1300);
DISPLAY 0.553191 (2450 1300);
PAINT GREEN (2450 1300);
DISPLAY INVISIBLE (2450 1300);
FORCEPROP 2 LAST ROOM DDR4_CH_A
J 0
(2450 1155);
PAINT ORANGE (2450 1155);
DISPLAY INVISIBLE (2450 1155);
FORCEPROP 1 LAST PATH I265
J 2
(2375 1150);
DISPLAY 1.404255 (2375 1150);
PAINT GREEN (2375 1150);
DISPLAY INVISIBLE (2375 1150);
FORCEPROP 1 LAST BODY_TYPE PLUMBING
J 2
(2495 1107);
DISPLAY 0.340426 (2495 1107);
PAINT GREEN (2495 1107);
DISPLAY INVISIBLE (2495 1107);
FORCEPROP 1 LAST SIZE 1B
J 2
(2375 1100);
DISPLAY 1.170213 (2375 1100);
PAINT GREEN (2375 1100);
DISPLAY INVISIBLE (2375 1100);
FORCEPROP 2 LAST BOM_COST MEM
J 0
(2450 1155);
PAINT ORANGE (2450 1155);
DISPLAY INVISIBLE (2450 1155);
FORCEPROP 2 LAST CDS_LIB mstr_symbols
J 0
(2450 1150);
DISPLAY 0.787234 (2450 1150);
PAINT MONO (2450 1150);
DISPLAY INVISIBLE (2450 1150);
FORCEPROP 1 LAST VOLTAGE 0
J 0
(2450 1150);
PAINT SKYBLUE (2450 1150);
DISPLAY INVISIBLE (2450 1150);
FORCEADD GND..1
R 2
(-5050 1400);
FORCEPROP 3 LASTPIN (-5050 1450) SIG_NAME GND\g
J 0
(-5040 1460);
DISPLAY 0.659574 (-5040 1460);
PAINT MONO (-5040 1460);
DISPLAY INVISIBLE (-5040 1460);
FORCEPROP 1 LAST HDL_POWER GND
J 2
(-5050 1550);
DISPLAY 0.553191 (-5050 1550);
PAINT GREEN (-5050 1550);
DISPLAY INVISIBLE (-5050 1550);
FORCEPROP 2 LAST ROOM DDR4_CH_A
J 0
(-5050 1405);
PAINT ORANGE (-5050 1405);
DISPLAY INVISIBLE (-5050 1405);
FORCEPROP 1 LAST PATH I267
J 2
(-5125 1400);
DISPLAY 1.404255 (-5125 1400);
PAINT GREEN (-5125 1400);
DISPLAY INVISIBLE (-5125 1400);
FORCEPROP 1 LAST BODY_TYPE PLUMBING
J 2
(-5005 1357);
DISPLAY 0.340426 (-5005 1357);
PAINT GREEN (-5005 1357);
DISPLAY INVISIBLE (-5005 1357);
FORCEPROP 1 LAST SIZE 1B
J 2
(-5125 1350);
DISPLAY 1.170213 (-5125 1350);
PAINT GREEN (-5125 1350);
DISPLAY INVISIBLE (-5125 1350);
FORCEPROP 2 LAST CDS_LIB mstr_symbols
J 0
(-5050 1400);
DISPLAY 0.787234 (-5050 1400);
PAINT MONO (-5050 1400);
DISPLAY INVISIBLE (-5050 1400);
FORCEPROP 2 LAST BOM_COST MEM
J 0
(-5050 1405);
PAINT ORANGE (-5050 1405);
DISPLAY INVISIBLE (-5050 1405);
FORCEPROP 1 LAST VOLTAGE 0
J 0
(-5050 1400);
PAINT SKYBLUE (-5050 1400);
DISPLAY INVISIBLE (-5050 1400);
FORCEADD OFFPAGE..1
(-3800 2300);
FORCEPROP 2 LAST $XR5 48 
J 0
(-4471 2300);
DISPLAY 0.638298 (-4471 2300);
PAINT MONO (-4471 2300);
FORCEPROP 2 LAST $XR4 47 
J 0
(-4381 2300);
DISPLAY 0.638298 (-4381 2300);
PAINT MONO (-4381 2300);
FORCEPROP 2 LAST $XR3 46 
J 0
(-4291 2300);
DISPLAY 0.638298 (-4291 2300);
PAINT MONO (-4291 2300);
FORCEPROP 2 LAST $XR2 45 
J 0
(-4201 2300);
DISPLAY 0.638298 (-4201 2300);
PAINT MONO (-4201 2300);
FORCEPROP 2 LAST $XR1 44 
J 0
(-4111 2300);
DISPLAY 0.638298 (-4111 2300);
PAINT MONO (-4111 2300);
FORCEPROP 2 LAST $XR0 21 
J 0
(-4021 2300);
DISPLAY 0.638298 (-4021 2300);
PAINT MONO (-4021 2300);
FORCEPROP 2 LAST PATH I269
J 0
(-4050 2350);
PAINT ORANGE (-4050 2350);
DISPLAY INVISIBLE (-4050 2350);
FORCEPROP 1 LAST COMMENT_BODY TRUE
J 0
(-3675 2200);
DISPLAY 0.936170 (-3675 2200);
PAINT GREEN (-3675 2200);
DISPLAY INVISIBLE (-3675 2200);
FORCEPROP 1 LAST OFFPAGE TRUE
J 0
(-3475 2175);
DISPLAY 0.936170 (-3475 2175);
PAINT GREEN (-3475 2175);
DISPLAY INVISIBLE (-3475 2175);
FORCEPROP 2 LAST CDS_LIB mstr_standard
J 0
(-3800 2300);
DISPLAY 0.787234 (-3800 2300);
PAINT MONO (-3800 2300);
DISPLAY INVISIBLE (-3800 2300);
FORCEADD TAP..6
(-3150 4150);
FORCEPROP 3 LASTPIN (-3100 4150) SIG_NAME M_A_MA<12>
J 0
(-3090 4160);
DISPLAY 0.659574 (-3090 4160);
PAINT MONO (-3090 4160);
DISPLAY INVISIBLE (-3090 4160);
FORCEPROP 1 LASTPIN (-3100 4150) BN 12
J 0
(-3150 4160);
DISPLAY 0.617021 (-3150 4160);
PAINT PINK (-3150 4160);
FORCEPROP 1 LAST PATH I27
J 0
(-3150 4150);
DISPLAY 0.936170 (-3150 4150);
PAINT GREEN (-3150 4150);
DISPLAY INVISIBLE (-3150 4150);
FORCEPROP 1 LAST HDL_TAP TRUE
J 0
(-2825 4025);
DISPLAY 1.234043 (-2825 4025);
PAINT GREEN (-2825 4025);
DISPLAY INVISIBLE (-2825 4025);
FORCEPROP 1 LAST BODY_TYPE PLUMBING
J 0
(-3150 4100);
DISPLAY 1.234043 (-3150 4100);
PAINT GREEN (-3150 4100);
DISPLAY INVISIBLE (-3150 4100);
FORCEPROP 2 LAST CDS_LIB mstr_standard
J 2
(-3150 4150);
DISPLAY 0.787234 (-3150 4150);
PAINT MONO (-3150 4150);
DISPLAY INVISIBLE (-3150 4150);
FORCEADD OFFPAGE..5
(-4025 2050);
FORCEPROP 2 LAST $XR23 94 
J 0
(-4519 2086);
DISPLAY 0.638298 (-4519 2086);
PAINT MONO (-4519 2086);
FORCEPROP 2 LAST $XR22 88 
J 0
(-4429 2086);
DISPLAY 0.638298 (-4429 2086);
PAINT MONO (-4429 2086);
FORCEPROP 2 LAST $XR21 87 
J 0
(-4339 2086);
DISPLAY 0.638298 (-4339 2086);
PAINT MONO (-4339 2086);
FORCEPROP 2 LAST $XR20 86 
J 0
(-4249 2086);
DISPLAY 0.638298 (-4249 2086);
PAINT MONO (-4249 2086);
FORCEPROP 2 LAST $XR19 85 
J 0
(-5059 2014);
DISPLAY 0.638298 (-5059 2014);
PAINT MONO (-5059 2014);
FORCEPROP 2 LAST $XR18 84 
J 0
(-4969 2014);
DISPLAY 0.638298 (-4969 2014);
PAINT MONO (-4969 2014);
FORCEPROP 2 LAST $XR17 83 
J 0
(-4879 2014);
DISPLAY 0.638298 (-4879 2014);
PAINT MONO (-4879 2014);
FORCEPROP 2 LAST $XR16 82 
J 0
(-4789 2014);
DISPLAY 0.638298 (-4789 2014);
PAINT MONO (-4789 2014);
FORCEPROP 2 LAST $XR15 81 
J 0
(-4699 2014);
DISPLAY 0.638298 (-4699 2014);
PAINT MONO (-4699 2014);
FORCEPROP 2 LAST $XR14 80 
J 0
(-4609 2014);
DISPLAY 0.638298 (-4609 2014);
PAINT MONO (-4609 2014);
FORCEPROP 2 LAST $XR13 79 
J 0
(-4519 2014);
DISPLAY 0.638298 (-4519 2014);
PAINT MONO (-4519 2014);
FORCEPROP 2 LAST $XR12 78 
J 0
(-4429 2014);
DISPLAY 0.638298 (-4429 2014);
PAINT MONO (-4429 2014);
FORCEPROP 2 LAST $XR11 77 
J 0
(-4339 2014);
DISPLAY 0.638298 (-4339 2014);
PAINT MONO (-4339 2014);
FORCEPROP 2 LAST $XR10 54 
J 0
(-4249 2014);
DISPLAY 0.638298 (-4249 2014);
PAINT MONO (-4249 2014);
FORCEPROP 2 LAST $XR9 53 
J 0
(-5059 2050);
DISPLAY 0.638298 (-5059 2050);
PAINT MONO (-5059 2050);
FORCEPROP 2 LAST $XR8 52 
J 0
(-4969 2050);
DISPLAY 0.638298 (-4969 2050);
PAINT MONO (-4969 2050);
FORCEPROP 2 LAST $XR7 51 
J 0
(-4879 2050);
DISPLAY 0.638298 (-4879 2050);
PAINT MONO (-4879 2050);
FORCEPROP 2 LAST $XR6 50 
J 0
(-4789 2050);
DISPLAY 0.638298 (-4789 2050);
PAINT MONO (-4789 2050);
FORCEPROP 2 LAST $XR5 49 
J 0
(-4699 2050);
DISPLAY 0.638298 (-4699 2050);
PAINT MONO (-4699 2050);
FORCEPROP 2 LAST $XR4 48 
J 0
(-4609 2050);
DISPLAY 0.638298 (-4609 2050);
PAINT MONO (-4609 2050);
FORCEPROP 2 LAST $XR3 47 
J 0
(-4519 2050);
DISPLAY 0.638298 (-4519 2050);
PAINT MONO (-4519 2050);
FORCEPROP 2 LAST $XR2 46 
J 0
(-4429 2050);
DISPLAY 0.638298 (-4429 2050);
PAINT MONO (-4429 2050);
FORCEPROP 2 LAST $XR1 45 
J 0
(-4339 2050);
DISPLAY 0.638298 (-4339 2050);
PAINT MONO (-4339 2050);
FORCEPROP 2 LAST $XR0 44 
J 0
(-4249 2050);
DISPLAY 0.638298 (-4249 2050);
PAINT MONO (-4249 2050);
FORCEPROP 2 LAST PATH I270
J 0
(-4300 2100);
PAINT ORANGE (-4300 2100);
DISPLAY INVISIBLE (-4300 2100);
FORCEPROP 1 LAST COMMENT_BODY TRUE
J 0
(-3925 1975);
DISPLAY 1.404255 (-3925 1975);
PAINT GREEN (-3925 1975);
DISPLAY INVISIBLE (-3925 1975);
FORCEPROP 1 LAST OFFPAGE TRUE
J 0
(-3700 1925);
DISPLAY 1.404255 (-3700 1925);
PAINT GREEN (-3700 1925);
DISPLAY INVISIBLE (-3700 1925);
FORCEPROP 2 LAST CDS_LIB mstr_standard
J 0
(-4025 2050);
DISPLAY 0.787234 (-4025 2050);
PAINT MONO (-4025 2050);
DISPLAY INVISIBLE (-4025 2050);
FORCEADD GND..1
(-4350 800);
FORCEPROP 3 LASTPIN (-4350 850) SIG_NAME GND\g
J 0
(-4340 860);
DISPLAY 0.659574 (-4340 860);
PAINT MONO (-4340 860);
DISPLAY INVISIBLE (-4340 860);
FORCEPROP 1 LAST HDL_POWER GND
J 0
(-4350 950);
DISPLAY 1.404255 (-4350 950);
PAINT GREEN (-4350 950);
DISPLAY INVISIBLE (-4350 950);
FORCEPROP 2 LAST ROOM DDR4_CH_A
J 0
(-4350 805);
PAINT ORANGE (-4350 805);
DISPLAY INVISIBLE (-4350 805);
FORCEPROP 1 LAST PATH I271
J 0
(-4275 800);
DISPLAY 1.404255 (-4275 800);
PAINT GREEN (-4275 800);
DISPLAY INVISIBLE (-4275 800);
FORCEPROP 1 LAST BODY_TYPE PLUMBING
J 0
(-4395 757);
DISPLAY 0.340426 (-4395 757);
PAINT GREEN (-4395 757);
DISPLAY INVISIBLE (-4395 757);
FORCEPROP 2 LAST BOM_COST MEM
J 0
(-4350 805);
PAINT ORANGE (-4350 805);
DISPLAY INVISIBLE (-4350 805);
FORCEPROP 2 LAST CDS_LIB mstr_symbols
J 0
(-4350 800);
PAINT ORANGE (-4350 800);
DISPLAY INVISIBLE (-4350 800);
FORCEPROP 1 LAST SIZE 1B
J 0
(-4275 750);
DISPLAY 1.787234 (-4275 750);
PAINT GREEN (-4275 750);
DISPLAY INVISIBLE (-4275 750);
FORCEPROP 1 LAST VOLTAGE 0
J 0
(-4350 800);
PAINT SKYBLUE (-4350 800);
DISPLAY INVISIBLE (-4350 800);
FORCEADD CAP_A..1
R 2
(-4350 1050);
FORCEPROP 1 LAST PACK_TYPE 0402V
J 2
(-4400 850);
DISPLAY 0.617021 (-4400 850);
PAINT SKYBLUE (-4400 850);
FORCEPROP 1 LASTPIN (-4350 950) $PN 2
J 2
(-4360 930);
DISPLAY 0.787234 (-4360 930);
PAINT ORANGE (-4360 930);
FORCEPROP 1 LASTPIN (-4350 1150) $PN 1
J 2
(-4360 1130);
DISPLAY 0.787234 (-4360 1130);
PAINT ORANGE (-4360 1130);
FORCEPROP 1 LAST LOCATION C4F10
J 2
(-4400 1150);
DISPLAY 0.617021 (-4400 1150);
PAINT AQUA (-4400 1150);
FORCEPROP 1 LAST PART_NUMBER A36096-045
J 2
(-4400 900);
DISPLAY 0.617021 (-4400 900);
PAINT BLUE (-4400 900);
FORCEPROP 1 LAST VALUE 0.01UF
J 2
(-4400 1100);
DISPLAY 0.617021 (-4400 1100);
PAINT SKYBLUE (-4400 1100);
FORCEPROP 1 LAST TOLERANCE 10%
J 2
(-4400 1000);
DISPLAY 0.617021 (-4400 1000);
PAINT SKYBLUE (-4400 1000);
FORCEPROP 1 LAST VOLTAGE 25V
J 2
(-4400 1050);
DISPLAY 0.617021 (-4400 1050);
PAINT SKYBLUE (-4400 1050);
FORCEPROP 1 LAST MATERIAL X7R
J 2
(-4400 950);
DISPLAY 0.617021 (-4400 950);
PAINT SKYBLUE (-4400 950);
FORCEPROP 2 LAST SEC 1
J 0
(-4400 1250);
PAINT MONO (-4400 1250);
DISPLAY INVISIBLE (-4400 1250);
FORCEPROP 2 LAST SEC_TYPE 0402V
J 0
(-4400 1250);
DISPLAY 1.021277 (-4400 1250);
PAINT ORANGE (-4400 1250);
DISPLAY INVISIBLE (-4400 1250);
FORCEPROP 2 LAST CDS_LOCATION C4F10
J 2
(-4400 1150);
DISPLAY 0.617021 (-4400 1150);
PAINT AQUA (-4400 1150);
DISPLAY INVISIBLE (-4400 1150);
FORCEPROP 2 LAST BOM_COST MEM
J 0
(-4350 1050);
PAINT ORANGE (-4350 1050);
DISPLAY INVISIBLE (-4350 1050);
FORCEPROP 2 LAST CDS_LIB dev_discrete
J 0
(-4350 1050);
PAINT ORANGE (-4350 1050);
DISPLAY INVISIBLE (-4350 1050);
FORCEPROP 2 LAST ROOM DDR4_CH_A
J 0
(-4350 1050);
PAINT ORANGE (-4350 1050);
DISPLAY INVISIBLE (-4350 1050);
FORCEPROP 1 LAST PATH I272
J 2
(-4400 1200);
DISPLAY 0.978723 (-4400 1200);
PAINT WHITE (-4400 1200);
DISPLAY INVISIBLE (-4400 1200);
FORCEADD PVPP_ABC..1
(-750 2700);
FORCEPROP 3 LASTPIN (-750 2650) SIG_NAME PVPP_ABC\g
J 0
(-740 2660);
DISPLAY 0.659574 (-740 2660);
PAINT MONO (-740 2660);
DISPLAY INVISIBLE (-740 2660);
FORCEPROP 1 LAST HDL_POWER PVPP_ABC
J 1
(-750 2750);
DISPLAY 0.872340 (-750 2750);
PAINT GREEN (-750 2750);
DISPLAY INVISIBLE (-750 2750);
FORCEPROP 2 LAST ROOM DDR4_CH_A
J 0
(-750 2800);
PAINT ORANGE (-750 2800);
DISPLAY INVISIBLE (-750 2800);
FORCEPROP 1 LAST PATH I273
J 0
(-700 2725);
DISPLAY 0.872340 (-700 2725);
PAINT AQUA (-700 2725);
DISPLAY INVISIBLE (-700 2725);
FORCEPROP 1 LAST BODY_TYPE PLUMBING
J 0
(-795 2657);
DISPLAY 0.340426 (-795 2657);
PAINT GREEN (-795 2657);
DISPLAY INVISIBLE (-795 2657);
FORCEPROP 2 LAST CDS_LIB mstr_symbols
J 0
(-750 2700);
PAINT ORANGE (-750 2700);
DISPLAY INVISIBLE (-750 2700);
FORCEPROP 0 LAST BOM_COST MEM
J 0
(-750 2800);
PAINT ORANGE (-750 2800);
DISPLAY INVISIBLE (-750 2800);
FORCEPROP 1 LAST VOLTAGE 2.5V
J 0
(-795 2657);
DISPLAY 0.340426 (-795 2657);
PAINT SKYBLUE (-795 2657);
DISPLAY INVISIBLE (-795 2657);
FORCEADD PVPP_ABC..1
(-5050 1750);
FORCEPROP 3 LASTPIN (-5050 1700) SIG_NAME PVPP_ABC\g
J 0
(-5040 1710);
DISPLAY 0.659574 (-5040 1710);
PAINT MONO (-5040 1710);
DISPLAY INVISIBLE (-5040 1710);
FORCEPROP 1 LAST HDL_POWER PVPP_ABC
J 1
(-5050 1800);
DISPLAY 0.872340 (-5050 1800);
PAINT GREEN (-5050 1800);
DISPLAY INVISIBLE (-5050 1800);
FORCEPROP 2 LAST ROOM DDR4_CH_A
J 0
(-5050 1850);
PAINT ORANGE (-5050 1850);
DISPLAY INVISIBLE (-5050 1850);
FORCEPROP 1 LAST PATH I274
J 0
(-5000 1775);
DISPLAY 0.872340 (-5000 1775);
PAINT AQUA (-5000 1775);
DISPLAY INVISIBLE (-5000 1775);
FORCEPROP 1 LAST BODY_TYPE PLUMBING
J 0
(-5095 1707);
DISPLAY 0.340426 (-5095 1707);
PAINT GREEN (-5095 1707);
DISPLAY INVISIBLE (-5095 1707);
FORCEPROP 2 LAST CDS_LIB mstr_symbols
J 0
(-5050 1750);
PAINT ORANGE (-5050 1750);
DISPLAY INVISIBLE (-5050 1750);
FORCEPROP 0 LAST BOM_COST MEM
J 0
(-5050 1850);
PAINT ORANGE (-5050 1850);
DISPLAY INVISIBLE (-5050 1850);
FORCEPROP 1 LAST VOLTAGE 2.5V
J 0
(-5095 1707);
DISPLAY 0.340426 (-5095 1707);
PAINT SKYBLUE (-5095 1707);
DISPLAY INVISIBLE (-5095 1707);
FORCEADD PVTT_ABC..1
(-900 2400);
FORCEPROP 3 LASTPIN (-900 2350) SIG_NAME PVTT_ABC\g
J 0
(-890 2360);
DISPLAY 0.659574 (-890 2360);
PAINT MONO (-890 2360);
DISPLAY INVISIBLE (-890 2360);
FORCEPROP 1 LAST HDL_POWER PVTT_ABC
J 1
(-900 2450);
DISPLAY 0.872340 (-900 2450);
PAINT GREEN (-900 2450);
DISPLAY INVISIBLE (-900 2450);
FORCEPROP 2 LAST ROOM DDR4_CH_A
J 0
(-900 2405);
PAINT ORANGE (-900 2405);
DISPLAY INVISIBLE (-900 2405);
FORCEPROP 1 LAST PATH I275
J 0
(-850 2425);
DISPLAY 0.872340 (-850 2425);
PAINT AQUA (-850 2425);
DISPLAY INVISIBLE (-850 2425);
FORCEPROP 1 LAST BODY_TYPE PLUMBING
J 0
(-945 2357);
DISPLAY 0.340426 (-945 2357);
PAINT GREEN (-945 2357);
DISPLAY INVISIBLE (-945 2357);
FORCEPROP 2 LAST CDS_LIB mstr_symbols
J 0
(-900 2400);
PAINT ORANGE (-900 2400);
DISPLAY INVISIBLE (-900 2400);
FORCEPROP 2 LAST BOM_COST MEM
J 0
(-900 2405);
PAINT ORANGE (-900 2405);
DISPLAY INVISIBLE (-900 2405);
FORCEPROP 1 LAST VOLTAGE 0.6V
J 0
(-945 2357);
DISPLAY 0.340426 (-945 2357);
PAINT SKYBLUE (-945 2357);
DISPLAY INVISIBLE (-945 2357);
FORCEADD OFFPAGE..1
(-3800 950);
FORCEPROP 2 LAST $XR5 48 
J 0
(-4111 914);
DISPLAY 0.638298 (-4111 914);
PAINT MONO (-4111 914);
FORCEPROP 2 LAST $XR4 47 
J 0
(-4021 914);
DISPLAY 0.638298 (-4021 914);
PAINT MONO (-4021 914);
FORCEPROP 2 LAST $XR3 46 
J 0
(-4291 950);
DISPLAY 0.638298 (-4291 950);
PAINT MONO (-4291 950);
FORCEPROP 2 LAST $XR2 45 
J 0
(-4201 950);
DISPLAY 0.638298 (-4201 950);
PAINT MONO (-4201 950);
FORCEPROP 2 LAST $XR1 44 
J 0
(-4111 950);
DISPLAY 0.638298 (-4111 950);
PAINT MONO (-4111 950);
FORCEPROP 2 LAST $XR0 89 
J 0
(-4021 950);
DISPLAY 0.638298 (-4021 950);
PAINT MONO (-4021 950);
FORCEPROP 2 LAST PATH I276
J 0
(-3750 1025);
PAINT ORANGE (-3750 1025);
DISPLAY INVISIBLE (-3750 1025);
FORCEPROP 1 LAST COMMENT_BODY TRUE
J 0
(-3675 850);
DISPLAY 0.936170 (-3675 850);
PAINT GREEN (-3675 850);
DISPLAY INVISIBLE (-3675 850);
FORCEPROP 1 LAST OFFPAGE TRUE
J 0
(-3475 825);
DISPLAY 0.936170 (-3475 825);
PAINT GREEN (-3475 825);
DISPLAY INVISIBLE (-3475 825);
FORCEPROP 2 LAST CDS_LIB mstr_standard
J 0
(-3800 950);
PAINT ORANGE (-3800 950);
DISPLAY INVISIBLE (-3800 950);
FORCEADD TAP..6
(-3150 4100);
FORCEPROP 3 LASTPIN (-3100 4100) SIG_NAME M_A_MA<11>
J 0
(-3090 4110);
DISPLAY 0.659574 (-3090 4110);
PAINT MONO (-3090 4110);
DISPLAY INVISIBLE (-3090 4110);
FORCEPROP 1 LASTPIN (-3100 4100) BN 11
J 0
(-3150 4110);
DISPLAY 0.617021 (-3150 4110);
PAINT PINK (-3150 4110);
FORCEPROP 1 LAST PATH I28
J 0
(-3150 4100);
DISPLAY 0.936170 (-3150 4100);
PAINT GREEN (-3150 4100);
DISPLAY INVISIBLE (-3150 4100);
FORCEPROP 1 LAST HDL_TAP TRUE
J 0
(-2825 3975);
DISPLAY 1.234043 (-2825 3975);
PAINT GREEN (-2825 3975);
DISPLAY INVISIBLE (-2825 3975);
FORCEPROP 1 LAST BODY_TYPE PLUMBING
J 0
(-3150 4050);
DISPLAY 1.234043 (-3150 4050);
PAINT GREEN (-3150 4050);
DISPLAY INVISIBLE (-3150 4050);
FORCEPROP 2 LAST CDS_LIB mstr_standard
J 2
(-3150 4100);
DISPLAY 0.787234 (-3150 4100);
PAINT MONO (-3150 4100);
DISPLAY INVISIBLE (-3150 4100);
FORCEADD P12V_NVDIMM_ABC..1
(600 2775);
FORCEPROP 3 LASTPIN (600 2725) SIG_NAME P12V_NVDIMM_ABC\g
J 0
(610 2735);
DISPLAY 0.659574 (610 2735);
PAINT MONO (610 2735);
DISPLAY INVISIBLE (610 2735);
FORCEPROP 1 LAST HDL_POWER P12V_NVDIMM_ABC
J 1
(600 2800);
DISPLAY 0.872340 (600 2800);
PAINT GREEN (600 2800);
DISPLAY INVISIBLE (600 2800);
FORCEPROP 1 LAST PATH I289
J 0
(650 2800);
DISPLAY 0.872340 (650 2800);
PAINT AQUA (650 2800);
DISPLAY INVISIBLE (650 2800);
FORCEPROP 1 LAST BODY_TYPE PLUMBING
J 0
(555 2732);
DISPLAY 0.340426 (555 2732);
PAINT GREEN (555 2732);
DISPLAY INVISIBLE (555 2732);
FORCEPROP 2 LAST CDS_LIB mstr_symbols
J 0
(600 2775);
PAINT ORANGE (600 2775);
DISPLAY INVISIBLE (600 2775);
FORCEPROP 1 LAST VOLTAGE 12.0
J 0
(555 2732);
DISPLAY 0.340426 (555 2732);
PAINT SKYBLUE (555 2732);
DISPLAY INVISIBLE (555 2732);
FORCEADD TAP..6
(-3150 4050);
FORCEPROP 3 LASTPIN (-3100 4050) SIG_NAME M_A_MA<10>
J 0
(-3090 4060);
DISPLAY 0.659574 (-3090 4060);
PAINT MONO (-3090 4060);
DISPLAY INVISIBLE (-3090 4060);
FORCEPROP 1 LASTPIN (-3100 4050) BN 10
J 0
(-3150 4060);
DISPLAY 0.617021 (-3150 4060);
PAINT PINK (-3150 4060);
FORCEPROP 1 LAST PATH I29
J 0
(-3150 4050);
DISPLAY 0.936170 (-3150 4050);
PAINT GREEN (-3150 4050);
DISPLAY INVISIBLE (-3150 4050);
FORCEPROP 1 LAST HDL_TAP TRUE
J 0
(-2825 3925);
DISPLAY 1.234043 (-2825 3925);
PAINT GREEN (-2825 3925);
DISPLAY INVISIBLE (-2825 3925);
FORCEPROP 1 LAST BODY_TYPE PLUMBING
J 0
(-3150 4000);
DISPLAY 1.234043 (-3150 4000);
PAINT GREEN (-3150 4000);
DISPLAY INVISIBLE (-3150 4000);
FORCEPROP 2 LAST CDS_LIB mstr_standard
J 2
(-3150 4050);
DISPLAY 0.787234 (-3150 4050);
PAINT MONO (-3150 4050);
DISPLAY INVISIBLE (-3150 4050);
FORCEADD TAP..6
(-3150 4000);
FORCEPROP 3 LASTPIN (-3100 4000) SIG_NAME M_A_MA<9>
J 0
(-3090 4010);
DISPLAY 0.659574 (-3090 4010);
PAINT MONO (-3090 4010);
DISPLAY INVISIBLE (-3090 4010);
FORCEPROP 1 LASTPIN (-3100 4000) BN 9
J 0
(-3150 4010);
DISPLAY 0.617021 (-3150 4010);
PAINT PINK (-3150 4010);
FORCEPROP 1 LAST PATH I30
J 0
(-3150 4000);
DISPLAY 0.936170 (-3150 4000);
PAINT GREEN (-3150 4000);
DISPLAY INVISIBLE (-3150 4000);
FORCEPROP 1 LAST HDL_TAP TRUE
J 0
(-2825 3875);
DISPLAY 1.234043 (-2825 3875);
PAINT GREEN (-2825 3875);
DISPLAY INVISIBLE (-2825 3875);
FORCEPROP 1 LAST BODY_TYPE PLUMBING
J 0
(-3150 3950);
DISPLAY 1.234043 (-3150 3950);
PAINT GREEN (-3150 3950);
DISPLAY INVISIBLE (-3150 3950);
FORCEPROP 2 LAST CDS_LIB mstr_standard
J 2
(-3150 4000);
DISPLAY 0.787234 (-3150 4000);
PAINT MONO (-3150 4000);
DISPLAY INVISIBLE (-3150 4000);
FORCEADD TAP..6
(-3150 3950);
FORCEPROP 3 LASTPIN (-3100 3950) SIG_NAME M_A_MA<8>
J 0
(-3090 3960);
DISPLAY 0.659574 (-3090 3960);
PAINT MONO (-3090 3960);
DISPLAY INVISIBLE (-3090 3960);
FORCEPROP 1 LASTPIN (-3100 3950) BN 8
J 0
(-3150 3960);
DISPLAY 0.617021 (-3150 3960);
PAINT PINK (-3150 3960);
FORCEPROP 1 LAST PATH I31
J 0
(-3150 3950);
DISPLAY 0.936170 (-3150 3950);
PAINT GREEN (-3150 3950);
DISPLAY INVISIBLE (-3150 3950);
FORCEPROP 1 LAST HDL_TAP TRUE
J 0
(-2825 3825);
DISPLAY 1.234043 (-2825 3825);
PAINT GREEN (-2825 3825);
DISPLAY INVISIBLE (-2825 3825);
FORCEPROP 1 LAST BODY_TYPE PLUMBING
J 0
(-3150 3900);
DISPLAY 1.234043 (-3150 3900);
PAINT GREEN (-3150 3900);
DISPLAY INVISIBLE (-3150 3900);
FORCEPROP 2 LAST CDS_LIB mstr_standard
J 2
(-3150 3950);
DISPLAY 0.787234 (-3150 3950);
PAINT MONO (-3150 3950);
DISPLAY INVISIBLE (-3150 3950);
FORCEADD TAP..6
(-3150 3850);
FORCEPROP 3 LASTPIN (-3100 3850) SIG_NAME M_A_MA<6>
J 0
(-3090 3860);
DISPLAY 0.659574 (-3090 3860);
PAINT MONO (-3090 3860);
DISPLAY INVISIBLE (-3090 3860);
FORCEPROP 1 LASTPIN (-3100 3850) BN 6
J 0
(-3150 3860);
DISPLAY 0.617021 (-3150 3860);
PAINT PINK (-3150 3860);
FORCEPROP 1 LAST PATH I32
J 0
(-3150 3850);
DISPLAY 0.936170 (-3150 3850);
PAINT GREEN (-3150 3850);
DISPLAY INVISIBLE (-3150 3850);
FORCEPROP 1 LAST HDL_TAP TRUE
J 0
(-2825 3725);
DISPLAY 1.234043 (-2825 3725);
PAINT GREEN (-2825 3725);
DISPLAY INVISIBLE (-2825 3725);
FORCEPROP 1 LAST BODY_TYPE PLUMBING
J 0
(-3150 3800);
DISPLAY 1.234043 (-3150 3800);
PAINT GREEN (-3150 3800);
DISPLAY INVISIBLE (-3150 3800);
FORCEPROP 2 LAST CDS_LIB mstr_standard
J 2
(-3150 3850);
DISPLAY 0.787234 (-3150 3850);
PAINT MONO (-3150 3850);
DISPLAY INVISIBLE (-3150 3850);
FORCEADD TAP..6
(-3150 3900);
FORCEPROP 3 LASTPIN (-3100 3900) SIG_NAME M_A_MA<7>
J 0
(-3090 3910);
DISPLAY 0.659574 (-3090 3910);
PAINT MONO (-3090 3910);
DISPLAY INVISIBLE (-3090 3910);
FORCEPROP 1 LASTPIN (-3100 3900) BN 7
J 0
(-3150 3910);
DISPLAY 0.617021 (-3150 3910);
PAINT PINK (-3150 3910);
FORCEPROP 1 LAST PATH I33
J 0
(-3150 3900);
DISPLAY 0.936170 (-3150 3900);
PAINT GREEN (-3150 3900);
DISPLAY INVISIBLE (-3150 3900);
FORCEPROP 1 LAST HDL_TAP TRUE
J 0
(-2825 3775);
DISPLAY 1.234043 (-2825 3775);
PAINT GREEN (-2825 3775);
DISPLAY INVISIBLE (-2825 3775);
FORCEPROP 1 LAST BODY_TYPE PLUMBING
J 0
(-3150 3850);
DISPLAY 1.234043 (-3150 3850);
PAINT GREEN (-3150 3850);
DISPLAY INVISIBLE (-3150 3850);
FORCEPROP 2 LAST CDS_LIB mstr_standard
J 2
(-3150 3900);
DISPLAY 0.787234 (-3150 3900);
PAINT MONO (-3150 3900);
DISPLAY INVISIBLE (-3150 3900);
FORCEADD TAP..6
(-3150 3800);
FORCEPROP 3 LASTPIN (-3100 3800) SIG_NAME M_A_MA<5>
J 0
(-3090 3810);
DISPLAY 0.659574 (-3090 3810);
PAINT MONO (-3090 3810);
DISPLAY INVISIBLE (-3090 3810);
FORCEPROP 1 LASTPIN (-3100 3800) BN 5
J 0
(-3150 3810);
DISPLAY 0.617021 (-3150 3810);
PAINT PINK (-3150 3810);
FORCEPROP 1 LAST PATH I34
J 0
(-3150 3800);
DISPLAY 0.936170 (-3150 3800);
PAINT GREEN (-3150 3800);
DISPLAY INVISIBLE (-3150 3800);
FORCEPROP 1 LAST HDL_TAP TRUE
J 0
(-2825 3675);
DISPLAY 1.234043 (-2825 3675);
PAINT GREEN (-2825 3675);
DISPLAY INVISIBLE (-2825 3675);
FORCEPROP 1 LAST BODY_TYPE PLUMBING
J 0
(-3150 3750);
DISPLAY 1.234043 (-3150 3750);
PAINT GREEN (-3150 3750);
DISPLAY INVISIBLE (-3150 3750);
FORCEPROP 2 LAST CDS_LIB mstr_standard
J 2
(-3150 3800);
DISPLAY 0.787234 (-3150 3800);
PAINT MONO (-3150 3800);
DISPLAY INVISIBLE (-3150 3800);
FORCEADD TAP..6
(-3150 3700);
FORCEPROP 3 LASTPIN (-3100 3700) SIG_NAME M_A_MA<3>
J 0
(-3090 3710);
DISPLAY 0.659574 (-3090 3710);
PAINT MONO (-3090 3710);
DISPLAY INVISIBLE (-3090 3710);
FORCEPROP 1 LASTPIN (-3100 3700) BN 3
J 0
(-3150 3710);
DISPLAY 0.617021 (-3150 3710);
PAINT PINK (-3150 3710);
FORCEPROP 1 LAST PATH I35
J 0
(-3150 3700);
DISPLAY 0.936170 (-3150 3700);
PAINT GREEN (-3150 3700);
DISPLAY INVISIBLE (-3150 3700);
FORCEPROP 1 LAST HDL_TAP TRUE
J 0
(-2825 3575);
DISPLAY 1.234043 (-2825 3575);
PAINT GREEN (-2825 3575);
DISPLAY INVISIBLE (-2825 3575);
FORCEPROP 1 LAST BODY_TYPE PLUMBING
J 0
(-3150 3650);
DISPLAY 1.234043 (-3150 3650);
PAINT GREEN (-3150 3650);
DISPLAY INVISIBLE (-3150 3650);
FORCEPROP 2 LAST CDS_LIB mstr_standard
J 2
(-3150 3700);
DISPLAY 0.787234 (-3150 3700);
PAINT MONO (-3150 3700);
DISPLAY INVISIBLE (-3150 3700);
FORCEADD TAP..6
(-3150 3750);
FORCEPROP 3 LASTPIN (-3100 3750) SIG_NAME M_A_MA<4>
J 0
(-3090 3760);
DISPLAY 0.659574 (-3090 3760);
PAINT MONO (-3090 3760);
DISPLAY INVISIBLE (-3090 3760);
FORCEPROP 1 LASTPIN (-3100 3750) BN 4
J 0
(-3150 3760);
DISPLAY 0.617021 (-3150 3760);
PAINT PINK (-3150 3760);
FORCEPROP 1 LAST PATH I36
J 0
(-3150 3750);
DISPLAY 0.936170 (-3150 3750);
PAINT GREEN (-3150 3750);
DISPLAY INVISIBLE (-3150 3750);
FORCEPROP 1 LAST HDL_TAP TRUE
J 0
(-2825 3625);
DISPLAY 1.234043 (-2825 3625);
PAINT GREEN (-2825 3625);
DISPLAY INVISIBLE (-2825 3625);
FORCEPROP 1 LAST BODY_TYPE PLUMBING
J 0
(-3150 3700);
DISPLAY 1.234043 (-3150 3700);
PAINT GREEN (-3150 3700);
DISPLAY INVISIBLE (-3150 3700);
FORCEPROP 2 LAST CDS_LIB mstr_standard
J 2
(-3150 3750);
DISPLAY 0.787234 (-3150 3750);
PAINT MONO (-3150 3750);
DISPLAY INVISIBLE (-3150 3750);
FORCEADD TAP..6
(-3150 3650);
FORCEPROP 3 LASTPIN (-3100 3650) SIG_NAME M_A_MA<2>
J 0
(-3090 3660);
DISPLAY 0.659574 (-3090 3660);
PAINT MONO (-3090 3660);
DISPLAY INVISIBLE (-3090 3660);
FORCEPROP 1 LASTPIN (-3100 3650) BN 2
J 0
(-3150 3660);
DISPLAY 0.617021 (-3150 3660);
PAINT PINK (-3150 3660);
FORCEPROP 1 LAST PATH I37
J 0
(-3150 3650);
DISPLAY 0.936170 (-3150 3650);
PAINT GREEN (-3150 3650);
DISPLAY INVISIBLE (-3150 3650);
FORCEPROP 1 LAST HDL_TAP TRUE
J 0
(-2825 3525);
DISPLAY 1.234043 (-2825 3525);
PAINT GREEN (-2825 3525);
DISPLAY INVISIBLE (-2825 3525);
FORCEPROP 1 LAST BODY_TYPE PLUMBING
J 0
(-3150 3600);
DISPLAY 1.234043 (-3150 3600);
PAINT GREEN (-3150 3600);
DISPLAY INVISIBLE (-3150 3600);
FORCEPROP 2 LAST CDS_LIB mstr_standard
J 2
(-3150 3650);
DISPLAY 0.787234 (-3150 3650);
PAINT MONO (-3150 3650);
DISPLAY INVISIBLE (-3150 3650);
FORCEADD TAP..6
(-3150 3600);
FORCEPROP 3 LASTPIN (-3100 3600) SIG_NAME M_A_MA<1>
J 0
(-3090 3610);
DISPLAY 0.659574 (-3090 3610);
PAINT MONO (-3090 3610);
DISPLAY INVISIBLE (-3090 3610);
FORCEPROP 1 LASTPIN (-3100 3600) BN 1
J 0
(-3150 3610);
DISPLAY 0.617021 (-3150 3610);
PAINT PINK (-3150 3610);
FORCEPROP 1 LAST PATH I38
J 0
(-3150 3600);
DISPLAY 0.936170 (-3150 3600);
PAINT GREEN (-3150 3600);
DISPLAY INVISIBLE (-3150 3600);
FORCEPROP 1 LAST HDL_TAP TRUE
J 0
(-2825 3475);
DISPLAY 1.234043 (-2825 3475);
PAINT GREEN (-2825 3475);
DISPLAY INVISIBLE (-2825 3475);
FORCEPROP 1 LAST BODY_TYPE PLUMBING
J 0
(-3150 3550);
DISPLAY 1.234043 (-3150 3550);
PAINT GREEN (-3150 3550);
DISPLAY INVISIBLE (-3150 3550);
FORCEPROP 2 LAST CDS_LIB mstr_standard
J 2
(-3150 3600);
DISPLAY 0.787234 (-3150 3600);
PAINT MONO (-3150 3600);
DISPLAY INVISIBLE (-3150 3600);
FORCEADD TAP..6
(-3150 3550);
FORCEPROP 3 LASTPIN (-3100 3550) SIG_NAME M_A_MA<0>
J 0
(-3090 3560);
DISPLAY 0.659574 (-3090 3560);
PAINT MONO (-3090 3560);
DISPLAY INVISIBLE (-3090 3560);
FORCEPROP 1 LASTPIN (-3100 3550) BN 0
J 0
(-3150 3560);
DISPLAY 0.617021 (-3150 3560);
PAINT PINK (-3150 3560);
FORCEPROP 1 LAST PATH I39
J 0
(-3150 3550);
DISPLAY 0.936170 (-3150 3550);
PAINT GREEN (-3150 3550);
DISPLAY INVISIBLE (-3150 3550);
FORCEPROP 1 LAST HDL_TAP TRUE
J 0
(-2825 3425);
DISPLAY 1.234043 (-2825 3425);
PAINT GREEN (-2825 3425);
DISPLAY INVISIBLE (-2825 3425);
FORCEPROP 1 LAST BODY_TYPE PLUMBING
J 0
(-3150 3500);
DISPLAY 1.234043 (-3150 3500);
PAINT GREEN (-3150 3500);
DISPLAY INVISIBLE (-3150 3500);
FORCEPROP 2 LAST CDS_LIB mstr_standard
J 2
(-3150 3550);
DISPLAY 0.787234 (-3150 3550);
PAINT MONO (-3150 3550);
DISPLAY INVISIBLE (-3150 3550);
FORCEADD OFFPAGE..1
(-3800 4450);
FORCEPROP 2 LAST $XR1 44 
J 0
(-4111 4450);
DISPLAY 0.638298 (-4111 4450);
PAINT MONO (-4111 4450);
FORCEPROP 2 LAST $XR0 23 
J 0
(-4021 4450);
DISPLAY 0.638298 (-4021 4450);
PAINT MONO (-4021 4450);
FORCEPROP 2 LAST PATH I40
J 0
(-3750 4525);
DISPLAY 0.787234 (-3750 4525);
PAINT MONO (-3750 4525);
DISPLAY INVISIBLE (-3750 4525);
FORCEPROP 1 LAST COMMENT_BODY TRUE
J 0
(-3675 4350);
DISPLAY 0.936170 (-3675 4350);
PAINT GREEN (-3675 4350);
DISPLAY INVISIBLE (-3675 4350);
FORCEPROP 1 LAST OFFPAGE TRUE
J 0
(-3475 4325);
DISPLAY 0.936170 (-3475 4325);
PAINT GREEN (-3475 4325);
DISPLAY INVISIBLE (-3475 4325);
FORCEPROP 2 LAST CDS_LIB mstr_standard
J 0
(-3800 4450);
DISPLAY 0.787234 (-3800 4450);
PAINT MONO (-3800 4450);
DISPLAY INVISIBLE (-3800 4450);
FORCEADD OFFPAGE..1
(-3800 3400);
FORCEPROP 2 LAST $XR1 44 
J 0
(-4111 3400);
DISPLAY 0.638298 (-4111 3400);
PAINT MONO (-4111 3400);
FORCEPROP 2 LAST $XR0 23 
J 0
(-4021 3400);
DISPLAY 0.638298 (-4021 3400);
PAINT MONO (-4021 3400);
FORCEPROP 2 LAST PATH I41
J 0
(-3750 3475);
DISPLAY 0.787234 (-3750 3475);
PAINT MONO (-3750 3475);
DISPLAY INVISIBLE (-3750 3475);
FORCEPROP 1 LAST COMMENT_BODY TRUE
J 0
(-3675 3300);
DISPLAY 0.936170 (-3675 3300);
PAINT GREEN (-3675 3300);
DISPLAY INVISIBLE (-3675 3300);
FORCEPROP 1 LAST OFFPAGE TRUE
J 0
(-3475 3275);
DISPLAY 0.936170 (-3475 3275);
PAINT GREEN (-3475 3275);
DISPLAY INVISIBLE (-3475 3275);
FORCEPROP 2 LAST CDS_LIB mstr_standard
J 0
(-3800 3400);
DISPLAY 0.787234 (-3800 3400);
PAINT MONO (-3800 3400);
DISPLAY INVISIBLE (-3800 3400);
FORCEADD OFFPAGE..1
(-3800 3500);
FORCEPROP 2 LAST $XR1 44 
J 0
(-4111 3500);
DISPLAY 0.638298 (-4111 3500);
PAINT MONO (-4111 3500);
FORCEPROP 2 LAST $XR0 23 
J 0
(-4021 3500);
DISPLAY 0.638298 (-4021 3500);
PAINT MONO (-4021 3500);
FORCEPROP 2 LAST PATH I42
J 0
(-3750 3575);
DISPLAY 0.787234 (-3750 3575);
PAINT MONO (-3750 3575);
DISPLAY INVISIBLE (-3750 3575);
FORCEPROP 1 LAST COMMENT_BODY TRUE
J 0
(-3675 3400);
DISPLAY 0.936170 (-3675 3400);
PAINT GREEN (-3675 3400);
DISPLAY INVISIBLE (-3675 3400);
FORCEPROP 1 LAST OFFPAGE TRUE
J 0
(-3475 3375);
DISPLAY 0.936170 (-3475 3375);
PAINT GREEN (-3475 3375);
DISPLAY INVISIBLE (-3475 3375);
FORCEPROP 2 LAST CDS_LIB mstr_standard
J 0
(-3800 3500);
DISPLAY 0.787234 (-3800 3500);
PAINT MONO (-3800 3500);
DISPLAY INVISIBLE (-3800 3500);
FORCEADD TAP..6
(-3150 3300);
FORCEPROP 3 LASTPIN (-3100 3300) SIG_NAME M_A_BG<0>
J 0
(-3090 3310);
DISPLAY 0.659574 (-3090 3310);
PAINT MONO (-3090 3310);
DISPLAY INVISIBLE (-3090 3310);
FORCEPROP 1 LASTPIN (-3100 3300) BN 0
J 0
(-3150 3310);
DISPLAY 0.617021 (-3150 3310);
PAINT PINK (-3150 3310);
FORCEPROP 1 LAST PATH I43
J 0
(-3150 3300);
DISPLAY 0.936170 (-3150 3300);
PAINT GREEN (-3150 3300);
DISPLAY INVISIBLE (-3150 3300);
FORCEPROP 1 LAST HDL_TAP TRUE
J 0
(-2825 3175);
DISPLAY 1.234043 (-2825 3175);
PAINT GREEN (-2825 3175);
DISPLAY INVISIBLE (-2825 3175);
FORCEPROP 1 LAST BODY_TYPE PLUMBING
J 0
(-3150 3250);
DISPLAY 1.234043 (-3150 3250);
PAINT GREEN (-3150 3250);
DISPLAY INVISIBLE (-3150 3250);
FORCEPROP 2 LAST CDS_LIB mstr_standard
J 0
(-3150 3300);
DISPLAY 0.787234 (-3150 3300);
PAINT MONO (-3150 3300);
DISPLAY INVISIBLE (-3150 3300);
FORCEADD TAP..6
(-3150 3350);
FORCEPROP 3 LASTPIN (-3100 3350) SIG_NAME M_A_BG<1>
J 0
(-3090 3360);
DISPLAY 0.659574 (-3090 3360);
PAINT MONO (-3090 3360);
DISPLAY INVISIBLE (-3090 3360);
FORCEPROP 1 LASTPIN (-3100 3350) BN 1
J 0
(-3150 3360);
DISPLAY 0.617021 (-3150 3360);
PAINT PINK (-3150 3360);
FORCEPROP 1 LAST PATH I44
J 0
(-3150 3350);
DISPLAY 0.936170 (-3150 3350);
PAINT GREEN (-3150 3350);
DISPLAY INVISIBLE (-3150 3350);
FORCEPROP 1 LAST HDL_TAP TRUE
J 0
(-2825 3225);
DISPLAY 1.234043 (-2825 3225);
PAINT GREEN (-2825 3225);
DISPLAY INVISIBLE (-2825 3225);
FORCEPROP 1 LAST BODY_TYPE PLUMBING
J 0
(-3150 3300);
DISPLAY 1.234043 (-3150 3300);
PAINT GREEN (-3150 3300);
DISPLAY INVISIBLE (-3150 3300);
FORCEPROP 2 LAST CDS_LIB mstr_standard
J 0
(-3150 3350);
DISPLAY 0.787234 (-3150 3350);
PAINT MONO (-3150 3350);
DISPLAY INVISIBLE (-3150 3350);
FORCEADD TAP..6
(-3150 3450);
FORCEPROP 3 LASTPIN (-3100 3450) SIG_NAME M_A_BA<1>
J 0
(-3090 3460);
DISPLAY 0.659574 (-3090 3460);
PAINT MONO (-3090 3460);
DISPLAY INVISIBLE (-3090 3460);
FORCEPROP 1 LASTPIN (-3100 3450) BN 1
J 0
(-3150 3460);
DISPLAY 0.617021 (-3150 3460);
PAINT PINK (-3150 3460);
FORCEPROP 1 LAST PATH I45
J 0
(-3150 3450);
DISPLAY 0.936170 (-3150 3450);
PAINT GREEN (-3150 3450);
DISPLAY INVISIBLE (-3150 3450);
FORCEPROP 1 LAST HDL_TAP TRUE
J 0
(-2825 3325);
DISPLAY 1.234043 (-2825 3325);
PAINT GREEN (-2825 3325);
DISPLAY INVISIBLE (-2825 3325);
FORCEPROP 1 LAST BODY_TYPE PLUMBING
J 0
(-3150 3400);
DISPLAY 1.234043 (-3150 3400);
PAINT GREEN (-3150 3400);
DISPLAY INVISIBLE (-3150 3400);
FORCEPROP 2 LAST CDS_LIB mstr_standard
J 0
(-3150 3450);
DISPLAY 0.787234 (-3150 3450);
PAINT MONO (-3150 3450);
DISPLAY INVISIBLE (-3150 3450);
FORCEADD TAP..6
(-3150 3400);
FORCEPROP 3 LASTPIN (-3100 3400) SIG_NAME M_A_BA<0>
J 0
(-3090 3410);
DISPLAY 0.659574 (-3090 3410);
PAINT MONO (-3090 3410);
DISPLAY INVISIBLE (-3090 3410);
FORCEPROP 1 LASTPIN (-3100 3400) BN 0
J 0
(-3150 3410);
DISPLAY 0.617021 (-3150 3410);
PAINT PINK (-3150 3410);
FORCEPROP 1 LAST PATH I46
J 0
(-3150 3400);
DISPLAY 0.936170 (-3150 3400);
PAINT GREEN (-3150 3400);
DISPLAY INVISIBLE (-3150 3400);
FORCEPROP 1 LAST HDL_TAP TRUE
J 0
(-2825 3275);
DISPLAY 1.234043 (-2825 3275);
PAINT GREEN (-2825 3275);
DISPLAY INVISIBLE (-2825 3275);
FORCEPROP 1 LAST BODY_TYPE PLUMBING
J 0
(-3150 3350);
DISPLAY 1.234043 (-3150 3350);
PAINT GREEN (-3150 3350);
DISPLAY INVISIBLE (-3150 3350);
FORCEPROP 2 LAST CDS_LIB mstr_standard
J 0
(-3150 3400);
DISPLAY 0.787234 (-3150 3400);
PAINT MONO (-3150 3400);
DISPLAY INVISIBLE (-3150 3400);
FORCEADD OFFPAGE..1
(-3800 3000);
FORCEPROP 2 LAST $XR1 44 
J 0
(-4111 3000);
DISPLAY 0.638298 (-4111 3000);
PAINT MONO (-4111 3000);
FORCEPROP 2 LAST $XR0 23 
J 0
(-4021 3000);
DISPLAY 0.638298 (-4021 3000);
PAINT MONO (-4021 3000);
FORCEPROP 2 LAST PATH I47
J 0
(-3750 3075);
DISPLAY 0.787234 (-3750 3075);
PAINT MONO (-3750 3075);
DISPLAY INVISIBLE (-3750 3075);
FORCEPROP 1 LAST COMMENT_BODY TRUE
J 0
(-3675 2900);
DISPLAY 0.936170 (-3675 2900);
PAINT GREEN (-3675 2900);
DISPLAY INVISIBLE (-3675 2900);
FORCEPROP 1 LAST OFFPAGE TRUE
J 0
(-3475 2875);
DISPLAY 0.936170 (-3475 2875);
PAINT GREEN (-3475 2875);
DISPLAY INVISIBLE (-3475 2875);
FORCEPROP 2 LAST CDS_LIB mstr_standard
J 0
(-3800 3000);
DISPLAY 0.787234 (-3800 3000);
PAINT MONO (-3800 3000);
DISPLAY INVISIBLE (-3800 3000);
FORCEADD OFFPAGE..6
(-3800 2400);
FORCEPROP 2 LAST $XR1 44 
J 0
(-4139 2400);
DISPLAY 0.638298 (-4139 2400);
PAINT MONO (-4139 2400);
FORCEPROP 2 LAST $XR0 23 
J 0
(-4049 2400);
DISPLAY 0.638298 (-4049 2400);
PAINT MONO (-4049 2400);
FORCEPROP 2 LAST PATH I48
J 0
(-3750 2475);
DISPLAY 0.787234 (-3750 2475);
PAINT MONO (-3750 2475);
DISPLAY INVISIBLE (-3750 2475);
FORCEPROP 1 LAST COMMENT_BODY TRUE
J 0
(-3700 2325);
DISPLAY 0.936170 (-3700 2325);
PAINT GREEN (-3700 2325);
DISPLAY INVISIBLE (-3700 2325);
FORCEPROP 1 LAST OFFPAGE TRUE
J 0
(-3475 2275);
DISPLAY 0.936170 (-3475 2275);
PAINT GREEN (-3475 2275);
DISPLAY INVISIBLE (-3475 2275);
FORCEPROP 2 LAST CDS_LIB mstr_standard
J 0
(-3800 2400);
DISPLAY 0.787234 (-3800 2400);
PAINT MONO (-3800 2400);
DISPLAY INVISIBLE (-3800 2400);
FORCEADD TAP..6
(-3150 2350);
FORCEPROP 3 LASTPIN (-3100 2350) SIG_NAME M_A_ECC<6>
J 0
(-3090 2360);
DISPLAY 0.659574 (-3090 2360);
PAINT MONO (-3090 2360);
DISPLAY INVISIBLE (-3090 2360);
FORCEPROP 1 LASTPIN (-3100 2350) BN 6
J 0
(-3150 2360);
DISPLAY 0.617021 (-3150 2360);
PAINT PINK (-3150 2360);
FORCEPROP 1 LAST PATH I49
J 0
(-3150 2350);
DISPLAY 0.936170 (-3150 2350);
PAINT GREEN (-3150 2350);
DISPLAY INVISIBLE (-3150 2350);
FORCEPROP 1 LAST HDL_TAP TRUE
J 0
(-2825 2225);
DISPLAY 1.234043 (-2825 2225);
PAINT GREEN (-2825 2225);
DISPLAY INVISIBLE (-2825 2225);
FORCEPROP 1 LAST BODY_TYPE PLUMBING
J 0
(-3150 2300);
DISPLAY 1.234043 (-3150 2300);
PAINT GREEN (-3150 2300);
DISPLAY INVISIBLE (-3150 2300);
FORCEPROP 2 LAST CDS_LIB mstr_standard
J 0
(-3150 2350);
DISPLAY 0.787234 (-3150 2350);
PAINT MONO (-3150 2350);
DISPLAY INVISIBLE (-3150 2350);
FORCEADD TAP..6
(-3150 2300);
FORCEPROP 3 LASTPIN (-3100 2300) SIG_NAME M_A_ECC<7>
J 0
(-3090 2310);
DISPLAY 0.659574 (-3090 2310);
PAINT MONO (-3090 2310);
DISPLAY INVISIBLE (-3090 2310);
FORCEPROP 1 LASTPIN (-3100 2300) BN 7
J 0
(-3150 2310);
DISPLAY 0.617021 (-3150 2310);
PAINT PINK (-3150 2310);
FORCEPROP 1 LAST PATH I50
J 0
(-3150 2300);
DISPLAY 0.936170 (-3150 2300);
PAINT GREEN (-3150 2300);
DISPLAY INVISIBLE (-3150 2300);
FORCEPROP 1 LAST HDL_TAP TRUE
J 0
(-2825 2175);
DISPLAY 1.234043 (-2825 2175);
PAINT GREEN (-2825 2175);
DISPLAY INVISIBLE (-2825 2175);
FORCEPROP 1 LAST BODY_TYPE PLUMBING
J 0
(-3150 2250);
DISPLAY 1.234043 (-3150 2250);
PAINT GREEN (-3150 2250);
DISPLAY INVISIBLE (-3150 2250);
FORCEPROP 2 LAST CDS_LIB mstr_standard
J 0
(-3150 2300);
DISPLAY 0.787234 (-3150 2300);
PAINT MONO (-3150 2300);
DISPLAY INVISIBLE (-3150 2300);
FORCEADD TAP..6
(-3150 2250);
FORCEPROP 3 LASTPIN (-3100 2250) SIG_NAME M_A_ECC<4>
J 0
(-3090 2260);
DISPLAY 0.659574 (-3090 2260);
PAINT MONO (-3090 2260);
DISPLAY INVISIBLE (-3090 2260);
FORCEPROP 1 LASTPIN (-3100 2250) BN 4
J 0
(-3150 2260);
DISPLAY 0.617021 (-3150 2260);
PAINT PINK (-3150 2260);
FORCEPROP 1 LAST PATH I51
J 0
(-3150 2250);
DISPLAY 0.936170 (-3150 2250);
PAINT GREEN (-3150 2250);
DISPLAY INVISIBLE (-3150 2250);
FORCEPROP 1 LAST HDL_TAP TRUE
J 0
(-2825 2125);
DISPLAY 1.234043 (-2825 2125);
PAINT GREEN (-2825 2125);
DISPLAY INVISIBLE (-2825 2125);
FORCEPROP 1 LAST BODY_TYPE PLUMBING
J 0
(-3150 2200);
DISPLAY 1.234043 (-3150 2200);
PAINT GREEN (-3150 2200);
DISPLAY INVISIBLE (-3150 2200);
FORCEPROP 2 LAST CDS_LIB mstr_standard
J 0
(-3150 2250);
DISPLAY 0.787234 (-3150 2250);
PAINT MONO (-3150 2250);
DISPLAY INVISIBLE (-3150 2250);
FORCEADD TAP..6
(-3150 2200);
FORCEPROP 3 LASTPIN (-3100 2200) SIG_NAME M_A_ECC<5>
J 0
(-3090 2210);
DISPLAY 0.659574 (-3090 2210);
PAINT MONO (-3090 2210);
DISPLAY INVISIBLE (-3090 2210);
FORCEPROP 1 LASTPIN (-3100 2200) BN 5
J 0
(-3150 2210);
DISPLAY 0.617021 (-3150 2210);
PAINT PINK (-3150 2210);
FORCEPROP 1 LAST PATH I52
J 0
(-3150 2200);
DISPLAY 0.936170 (-3150 2200);
PAINT GREEN (-3150 2200);
DISPLAY INVISIBLE (-3150 2200);
FORCEPROP 1 LAST HDL_TAP TRUE
J 0
(-2825 2075);
DISPLAY 1.234043 (-2825 2075);
PAINT GREEN (-2825 2075);
DISPLAY INVISIBLE (-2825 2075);
FORCEPROP 1 LAST BODY_TYPE PLUMBING
J 0
(-3150 2150);
DISPLAY 1.234043 (-3150 2150);
PAINT GREEN (-3150 2150);
DISPLAY INVISIBLE (-3150 2150);
FORCEPROP 2 LAST CDS_LIB mstr_standard
J 0
(-3150 2200);
DISPLAY 0.787234 (-3150 2200);
PAINT MONO (-3150 2200);
DISPLAY INVISIBLE (-3150 2200);
FORCEADD TAP..6
(-3150 2150);
FORCEPROP 3 LASTPIN (-3100 2150) SIG_NAME M_A_ECC<2>
J 0
(-3090 2160);
DISPLAY 0.659574 (-3090 2160);
PAINT MONO (-3090 2160);
DISPLAY INVISIBLE (-3090 2160);
FORCEPROP 1 LASTPIN (-3100 2150) BN 2
J 0
(-3150 2160);
DISPLAY 0.617021 (-3150 2160);
PAINT PINK (-3150 2160);
FORCEPROP 1 LAST PATH I53
J 0
(-3150 2150);
DISPLAY 0.936170 (-3150 2150);
PAINT GREEN (-3150 2150);
DISPLAY INVISIBLE (-3150 2150);
FORCEPROP 1 LAST HDL_TAP TRUE
J 0
(-2825 2025);
DISPLAY 1.234043 (-2825 2025);
PAINT GREEN (-2825 2025);
DISPLAY INVISIBLE (-2825 2025);
FORCEPROP 1 LAST BODY_TYPE PLUMBING
J 0
(-3150 2100);
DISPLAY 1.234043 (-3150 2100);
PAINT GREEN (-3150 2100);
DISPLAY INVISIBLE (-3150 2100);
FORCEPROP 2 LAST CDS_LIB mstr_standard
J 0
(-3150 2150);
DISPLAY 0.787234 (-3150 2150);
PAINT MONO (-3150 2150);
DISPLAY INVISIBLE (-3150 2150);
FORCEADD TAP..6
(-3150 2050);
FORCEPROP 3 LASTPIN (-3100 2050) SIG_NAME M_A_ECC<0>
J 0
(-3090 2060);
DISPLAY 0.659574 (-3090 2060);
PAINT MONO (-3090 2060);
DISPLAY INVISIBLE (-3090 2060);
FORCEPROP 1 LASTPIN (-3100 2050) BN 0
J 0
(-3150 2060);
DISPLAY 0.617021 (-3150 2060);
PAINT PINK (-3150 2060);
FORCEPROP 1 LAST PATH I54
J 0
(-3150 2050);
DISPLAY 0.936170 (-3150 2050);
PAINT GREEN (-3150 2050);
DISPLAY INVISIBLE (-3150 2050);
FORCEPROP 1 LAST HDL_TAP TRUE
J 0
(-2825 1925);
DISPLAY 1.234043 (-2825 1925);
PAINT GREEN (-2825 1925);
DISPLAY INVISIBLE (-2825 1925);
FORCEPROP 1 LAST BODY_TYPE PLUMBING
J 0
(-3150 2000);
DISPLAY 1.234043 (-3150 2000);
PAINT GREEN (-3150 2000);
DISPLAY INVISIBLE (-3150 2000);
FORCEPROP 2 LAST CDS_LIB mstr_standard
J 0
(-3150 2050);
DISPLAY 0.787234 (-3150 2050);
PAINT MONO (-3150 2050);
DISPLAY INVISIBLE (-3150 2050);
FORCEADD TAP..6
(-3150 2100);
FORCEPROP 3 LASTPIN (-3100 2100) SIG_NAME M_A_ECC<3>
J 0
(-3090 2110);
DISPLAY 0.659574 (-3090 2110);
PAINT MONO (-3090 2110);
DISPLAY INVISIBLE (-3090 2110);
FORCEPROP 1 LASTPIN (-3100 2100) BN 3
J 0
(-3150 2110);
DISPLAY 0.617021 (-3150 2110);
PAINT PINK (-3150 2110);
FORCEPROP 1 LAST PATH I55
J 0
(-3150 2100);
DISPLAY 0.936170 (-3150 2100);
PAINT GREEN (-3150 2100);
DISPLAY INVISIBLE (-3150 2100);
FORCEPROP 1 LAST HDL_TAP TRUE
J 0
(-2825 1975);
DISPLAY 1.234043 (-2825 1975);
PAINT GREEN (-2825 1975);
DISPLAY INVISIBLE (-2825 1975);
FORCEPROP 1 LAST BODY_TYPE PLUMBING
J 0
(-3150 2050);
DISPLAY 1.234043 (-3150 2050);
PAINT GREEN (-3150 2050);
DISPLAY INVISIBLE (-3150 2050);
FORCEPROP 2 LAST CDS_LIB mstr_standard
J 0
(-3150 2100);
DISPLAY 0.787234 (-3150 2100);
PAINT MONO (-3150 2100);
DISPLAY INVISIBLE (-3150 2100);
FORCEADD TAP..6
(-3150 2000);
FORCEPROP 3 LASTPIN (-3100 2000) SIG_NAME M_A_ECC<1>
J 0
(-3090 2010);
DISPLAY 0.659574 (-3090 2010);
PAINT MONO (-3090 2010);
DISPLAY INVISIBLE (-3090 2010);
FORCEPROP 1 LASTPIN (-3100 2000) BN 1
J 0
(-3150 2010);
DISPLAY 0.617021 (-3150 2010);
PAINT PINK (-3150 2010);
FORCEPROP 1 LAST PATH I56
J 0
(-3150 2000);
DISPLAY 0.936170 (-3150 2000);
PAINT GREEN (-3150 2000);
DISPLAY INVISIBLE (-3150 2000);
FORCEPROP 1 LAST HDL_TAP TRUE
J 0
(-2825 1875);
DISPLAY 1.234043 (-2825 1875);
PAINT GREEN (-2825 1875);
DISPLAY INVISIBLE (-2825 1875);
FORCEPROP 1 LAST BODY_TYPE PLUMBING
J 0
(-3150 1950);
DISPLAY 1.234043 (-3150 1950);
PAINT GREEN (-3150 1950);
DISPLAY INVISIBLE (-3150 1950);
FORCEPROP 2 LAST CDS_LIB mstr_standard
J 0
(-3150 2000);
DISPLAY 0.787234 (-3150 2000);
PAINT MONO (-3150 2000);
DISPLAY INVISIBLE (-3150 2000);
FORCEADD OFFPAGE..1
(-3800 2350);
FORCEPROP 2 LAST $XR1 44 
J 0
(-4141 2350);
DISPLAY 0.638298 (-4141 2350);
PAINT MONO (-4141 2350);
FORCEPROP 2 LAST $XR0 23 
J 0
(-4051 2350);
DISPLAY 0.638298 (-4051 2350);
PAINT MONO (-4051 2350);
FORCEPROP 2 LAST PATH I57
J 0
(-3750 2425);
DISPLAY 0.787234 (-3750 2425);
PAINT MONO (-3750 2425);
DISPLAY INVISIBLE (-3750 2425);
FORCEPROP 1 LAST COMMENT_BODY TRUE
J 0
(-3675 2250);
DISPLAY 0.936170 (-3675 2250);
PAINT GREEN (-3675 2250);
DISPLAY INVISIBLE (-3675 2250);
FORCEPROP 1 LAST OFFPAGE TRUE
J 0
(-3475 2225);
DISPLAY 0.936170 (-3475 2225);
PAINT GREEN (-3475 2225);
DISPLAY INVISIBLE (-3475 2225);
FORCEPROP 2 LAST CDS_LIB mstr_standard
J 0
(-3800 2350);
DISPLAY 0.787234 (-3800 2350);
PAINT MONO (-3800 2350);
DISPLAY INVISIBLE (-3800 2350);
FORCEADD OFFPAGE..5
(-4025 1750);
FORCEPROP 2 LAST $XR1 23 
J 0
(-4339 1750);
DISPLAY 0.638298 (-4339 1750);
PAINT MONO (-4339 1750);
FORCEPROP 2 LAST $XR0 44 
J 0
(-4249 1750);
DISPLAY 0.638298 (-4249 1750);
PAINT MONO (-4249 1750);
FORCEPROP 2 LAST PATH I59
J 0
(-3975 1825);
DISPLAY 0.787234 (-3975 1825);
PAINT MONO (-3975 1825);
DISPLAY INVISIBLE (-3975 1825);
FORCEPROP 1 LAST COMMENT_BODY TRUE
J 0
(-3925 1675);
DISPLAY 1.404255 (-3925 1675);
PAINT GREEN (-3925 1675);
DISPLAY INVISIBLE (-3925 1675);
FORCEPROP 1 LAST OFFPAGE TRUE
J 0
(-3700 1625);
DISPLAY 1.404255 (-3700 1625);
PAINT GREEN (-3700 1625);
DISPLAY INVISIBLE (-3700 1625);
FORCEPROP 2 LAST CDS_LIB mstr_standard
J 0
(-4025 1750);
DISPLAY 0.787234 (-4025 1750);
PAINT MONO (-4025 1750);
DISPLAY INVISIBLE (-4025 1750);
FORCEADD OFFPAGE..1
(-4025 1700);
FORCEPROP 2 LAST $XR1 44 
J 0
(-4366 1700);
DISPLAY 0.638298 (-4366 1700);
PAINT MONO (-4366 1700);
FORCEPROP 2 LAST $XR0 23 
J 0
(-4276 1700);
DISPLAY 0.638298 (-4276 1700);
PAINT MONO (-4276 1700);
FORCEPROP 2 LAST PATH I60
J 0
(-3975 1775);
DISPLAY 0.787234 (-3975 1775);
PAINT MONO (-3975 1775);
DISPLAY INVISIBLE (-3975 1775);
FORCEPROP 1 LAST COMMENT_BODY TRUE
J 0
(-3900 1600);
DISPLAY 0.936170 (-3900 1600);
PAINT GREEN (-3900 1600);
DISPLAY INVISIBLE (-3900 1600);
FORCEPROP 1 LAST OFFPAGE TRUE
J 0
(-3700 1575);
DISPLAY 0.936170 (-3700 1575);
PAINT GREEN (-3700 1575);
DISPLAY INVISIBLE (-3700 1575);
FORCEPROP 2 LAST CDS_LIB mstr_standard
J 0
(-4025 1700);
DISPLAY 0.787234 (-4025 1700);
PAINT MONO (-4025 1700);
DISPLAY INVISIBLE (-4025 1700);
FORCEADD OFFPAGE..1
(-4500 1250);
FORCEPROP 2 LAST $XR1 44 
J 0
(-4811 1250);
DISPLAY 0.638298 (-4811 1250);
PAINT MONO (-4811 1250);
FORCEPROP 2 LAST $XR0 98 
J 0
(-4721 1250);
DISPLAY 0.638298 (-4721 1250);
PAINT MONO (-4721 1250);
FORCEPROP 2 LAST PATH I61
J 0
(-4450 1325);
DISPLAY 0.787234 (-4450 1325);
PAINT MONO (-4450 1325);
DISPLAY INVISIBLE (-4450 1325);
FORCEPROP 1 LAST COMMENT_BODY TRUE
J 0
(-4375 1150);
DISPLAY 0.936170 (-4375 1150);
PAINT GREEN (-4375 1150);
DISPLAY INVISIBLE (-4375 1150);
FORCEPROP 1 LAST OFFPAGE TRUE
J 0
(-4175 1125);
DISPLAY 0.936170 (-4175 1125);
PAINT GREEN (-4175 1125);
DISPLAY INVISIBLE (-4175 1125);
FORCEPROP 2 LAST CDS_LIB mstr_standard
J 0
(-4500 1250);
DISPLAY 0.787234 (-4500 1250);
PAINT MONO (-4500 1250);
DISPLAY INVISIBLE (-4500 1250);
FORCEADD INTEL_CORP_BPAGE..1
(2625 225);
FORCEPROP 1 LAST CDS_CON_LAST_MODIFIED Fri Jun 16 17:48:16 2017
J 0
(1200 550);
DISPLAY 0.787234 (1200 550);
PAINT ORANGE (1200 550);
DISPLAY INVISIBLE (1200 550);
FORCEPROP 1 LAST CUSTOM_TXT_CDS <CURRENT_DESIGN_SHEET> OF <TOTAL_DESIGN_SHEETS>
J 0
(2125 250);
PAINT ORANGE (2125 250);
FORCEPROP 2 LAST CUSTOM_TXT_CDS <XR_PAGE_TITLE>
J 0
(-5265 5475);
DISPLAY 0.638298 (-5265 5475);
PAINT PINK (-5265 5475);
DISPLAY INVISIBLE (-5265 5475);
FORCEPROP 2 LAST CUSTOM_TXT_CDS <CON_LAST_MODIFIED>
J 0
(-1375 325);
DISPLAY 1.063830 (-1375 325);
PAINT ORANGE (-1375 325);
FORCEPROP 1 LAST SCH_TITLE CPU0 DDR4 CH A DIMM0
J 0
(-5325 275);
DISPLAY 1.212766 (-5325 275);
PAINT WHITE (-5325 275);
FORCEPROP 1 LAST COMMENT_BODY TRUE
J 0
(2635 235);
DISPLAY 0.382979 (2635 235);
PAINT GREEN (2635 235);
DISPLAY INVISIBLE (2635 235);
FORCEPROP 2 LAST CDS_LIB mstr_symbols
J 0
(2625 225);
DISPLAY 0.787234 (2625 225);
PAINT MONO (2625 225);
DISPLAY INVISIBLE (2625 225);
FORCEPROP 2 LAST PAGE_BORDER TRUE
J 0
(-5265 5475);
DISPLAY 0.680851 (-5265 5475);
PAINT PINK (-5265 5475);
DISPLAY INVISIBLE (-5265 5475);
FORCEPROP 2 LAST CDS_XR_PAGE_TITLE CR-43 : @BASEBOARD_FAB2_LIB.BASEBOARD_FAB2(SCH_1):PAGE43
J 0
(-5265 5475);
DISPLAY 0.638298 (-5265 5475);
PAINT PINK (-5265 5475);
DISPLAY INVISIBLE (-5265 5475);
FORCEADD BOM_NOTE..1
(-4975 4925);
FORCEPROP 0 LAST L1 STUFF FOR SKU A & B
J 0
(-5125 4825);
DISPLAY 1.063830 (-5125 4825);
PAINT WHITE (-5125 4825);
FORCEPROP 2 LAST ROOM SB_HEADERS
J 0
(-5125 4900);
DISPLAY 1.361702 (-5125 4900);
PAINT ORANGE (-5125 4900);
DISPLAY INVISIBLE (-5125 4900);
FORCEPROP 1 LAST COMMENT_BODY TRUE
J 0
(-4950 5025);
DISPLAY 1.319149 (-4950 5025);
PAINT ORANGE (-4950 5025);
DISPLAY INVISIBLE (-4950 5025);
FORCEPROP 2 LAST CDS_LIB mstr_symbols
J 0
(-4975 4925);
PAINT ORANGE (-4975 4925);
DISPLAY INVISIBLE (-4975 4925);
FORCEPROP 2 LAST BOM_COST SB
J 0
(-5125 4900);
DISPLAY 1.361702 (-5125 4900);
PAINT ORANGE (-5125 4900);
DISPLAY INVISIBLE (-5125 4900);
WIRE 16 -1 (-1125 2200)(-1125 2100);
WIRE 16 -1 (-1125 2100)(-750 2100);
WIRE 16 -1 (-750 2050)(-750 2100);
WIRE 16 -1 (-750 2100)(-600 2100);
WIRE 16 -1 (-750 2000)(-750 2050);
WIRE 16 -1 (-750 2050)(-600 2050);
WIRE 16 -1 (-750 1950)(-750 2000);
WIRE 16 -1 (-750 2000)(-600 2000);
WIRE 16 -1 (-750 1900)(-750 1950);
WIRE 16 -1 (-750 1950)(-600 1950);
WIRE 16 -1 (-750 1850)(-750 1900);
WIRE 16 -1 (-750 1900)(-600 1900);
WIRE 16 -1 (-750 1800)(-750 1850);
WIRE 16 -1 (-750 1850)(-600 1850);
WIRE 16 -1 (-750 1750)(-750 1800);
WIRE 16 -1 (-750 1800)(-600 1800);
WIRE 16 -1 (-750 1700)(-750 1750);
WIRE 16 -1 (-750 1750)(-600 1750);
WIRE 16 -1 (-750 1650)(-750 1700);
WIRE 16 -1 (-750 1700)(-600 1700);
WIRE 16 -1 (-750 1600)(-750 1650);
WIRE 16 -1 (-750 1650)(-600 1650);
WIRE 16 -1 (-750 1550)(-750 1600);
WIRE 16 -1 (-750 1600)(-600 1600);
WIRE 16 -1 (-750 1500)(-750 1550);
WIRE 16 -1 (-750 1550)(-600 1550);
WIRE 16 -1 (-750 1450)(-750 1500);
WIRE 16 -1 (-750 1500)(-600 1500);
WIRE 16 -1 (-750 1400)(-750 1450);
WIRE 16 -1 (-750 1450)(-600 1450);
WIRE 16 -1 (-750 1350)(-750 1400);
WIRE 16 -1 (-750 1400)(-600 1400);
WIRE 16 -1 (-750 1300)(-750 1350);
WIRE 16 -1 (-750 1350)(-600 1350);
WIRE 16 -1 (-750 1250)(-750 1300);
WIRE 16 -1 (-750 1300)(-600 1300);
WIRE 16 -1 (-750 1200)(-750 1250);
WIRE 16 -1 (-750 1250)(-600 1250);
WIRE 16 -1 (-750 1150)(-750 1200);
WIRE 16 -1 (-750 1200)(-600 1200);
WIRE 16 -1 (-750 1100)(-750 1150);
WIRE 16 -1 (-750 1150)(-600 1150);
WIRE 16 -1 (-750 1050)(-750 1100);
WIRE 16 -1 (-750 1100)(-600 1100);
WIRE 16 -1 (-750 1000)(-750 1050);
WIRE 16 -1 (-750 1050)(-600 1050);
WIRE 16 -1 (-750 950)(-750 1000);
WIRE 16 -1 (-750 1000)(-600 1000);
WIRE 16 -1 (-750 900)(-750 950);
WIRE 16 -1 (-750 950)(-600 950);
WIRE 16 -1 (-750 850)(-750 900);
WIRE 16 -1 (-750 900)(-600 900);
WIRE 16 -1 (-750 850)(-600 850);
WIRE 16 -1 (1050 1200)(1050 1300);
WIRE 16 -1 (1050 1300)(1050 1350);
WIRE 16 -1 (1050 1300)(1250 1300);
WIRE 16 -1 (1050 1350)(1050 1400);
WIRE 16 -1 (1050 1350)(1250 1350);
WIRE 16 -1 (1050 1400)(1050 1450);
WIRE 16 -1 (1050 1400)(1250 1400);
WIRE 16 -1 (1050 1450)(1050 1500);
WIRE 16 -1 (1050 1450)(1250 1450);
WIRE 16 -1 (1050 1500)(1050 1550);
WIRE 16 -1 (1050 1500)(1250 1500);
WIRE 16 -1 (1050 1550)(1050 1600);
WIRE 16 -1 (1050 1550)(1250 1550);
WIRE 16 -1 (1050 1600)(1050 1650);
WIRE 16 -1 (1050 1600)(1250 1600);
WIRE 16 -1 (1050 1650)(1050 1700);
WIRE 16 -1 (1050 1650)(1250 1650);
WIRE 16 -1 (1050 1700)(1050 1750);
WIRE 16 -1 (1050 1700)(1250 1700);
WIRE 16 -1 (1050 1750)(1050 1800);
WIRE 16 -1 (1050 1750)(1250 1750);
WIRE 16 -1 (1050 1800)(1050 1850);
WIRE 16 -1 (1050 1800)(1250 1800);
WIRE 16 -1 (1050 1850)(1050 1900);
WIRE 16 -1 (1050 1850)(1250 1850);
WIRE 16 -1 (1050 1900)(1050 1950);
WIRE 16 -1 (1050 1900)(1250 1900);
WIRE 16 -1 (1050 1950)(1050 2000);
WIRE 16 -1 (1050 1950)(1250 1950);
WIRE 16 -1 (1050 2000)(1050 2050);
WIRE 16 -1 (1050 2000)(1250 2000);
WIRE 16 -1 (1050 2050)(1050 2100);
WIRE 16 -1 (1050 2050)(1250 2050);
WIRE 16 -1 (1050 2100)(1050 2150);
WIRE 16 -1 (1050 2100)(1250 2100);
WIRE 16 -1 (1050 2150)(1050 2200);
WIRE 16 -1 (1050 2150)(1250 2150);
WIRE 16 -1 (1050 2200)(1050 2250);
WIRE 16 -1 (1050 2200)(1250 2200);
WIRE 16 -1 (1050 2250)(1050 2300);
WIRE 16 -1 (1050 2250)(1250 2250);
WIRE 16 -1 (1050 2300)(1050 2350);
WIRE 16 -1 (1050 2300)(1250 2300);
WIRE 16 -1 (1050 2350)(1050 2400);
WIRE 16 -1 (1050 2350)(1250 2350);
WIRE 16 -1 (1050 2400)(1050 2450);
WIRE 16 -1 (1050 2400)(1250 2400);
WIRE 16 -1 (1050 2450)(1050 2500);
WIRE 16 -1 (1050 2450)(1250 2450);
WIRE 16 -1 (1050 2500)(1050 2550);
WIRE 16 -1 (1050 2500)(1250 2500);
WIRE 16 -1 (1050 2550)(1050 2600);
WIRE 16 -1 (1050 2550)(1250 2550);
WIRE 16 -1 (1050 2600)(1050 2650);
WIRE 16 -1 (1050 2600)(1250 2600);
WIRE 16 -1 (1050 2650)(1050 2700);
WIRE 16 -1 (1050 2650)(1250 2650);
WIRE 16 -1 (1050 2700)(1050 2750);
WIRE 16 -1 (1050 2700)(1250 2700);
WIRE 16 -1 (1050 2750)(1050 2800);
WIRE 16 -1 (1050 2750)(1250 2750);
WIRE 16 -1 (1050 2800)(1050 2850);
WIRE 16 -1 (1050 2800)(1250 2800);
WIRE 16 -1 (1050 2850)(1050 2900);
WIRE 16 -1 (1050 2850)(1250 2850);
WIRE 16 -1 (1050 2900)(1050 2950);
WIRE 16 -1 (1050 2900)(1250 2900);
WIRE 16 -1 (1050 2950)(1050 3000);
WIRE 16 -1 (1050 2950)(1250 2950);
WIRE 16 -1 (1050 3000)(1050 3050);
WIRE 16 -1 (1050 3000)(1250 3000);
WIRE 16 -1 (1050 3050)(1050 3100);
WIRE 16 -1 (1050 3050)(1250 3050);
WIRE 16 -1 (1050 3100)(1050 3150);
WIRE 16 -1 (1050 3100)(1250 3100);
WIRE 16 -1 (1050 3150)(1050 3200);
WIRE 16 -1 (1050 3150)(1250 3150);
WIRE 16 -1 (1050 3200)(1050 3250);
WIRE 16 -1 (1050 3200)(1250 3200);
WIRE 16 -1 (1050 3250)(1050 3300);
WIRE 16 -1 (1050 3250)(1250 3250);
WIRE 16 -1 (1050 3300)(1050 3350);
WIRE 16 -1 (1050 3300)(1250 3300);
WIRE 16 -1 (1050 3350)(1050 3400);
WIRE 16 -1 (1050 3350)(1250 3350);
WIRE 16 -1 (1050 3400)(1050 3450);
WIRE 16 -1 (1050 3400)(1250 3400);
WIRE 16 -1 (1050 3450)(1050 3500);
WIRE 16 -1 (1050 3450)(1250 3450);
WIRE 16 -1 (1050 3500)(1050 3550);
WIRE 16 -1 (1050 3500)(1250 3500);
WIRE 16 -1 (1050 3550)(1050 3600);
WIRE 16 -1 (1050 3550)(1250 3550);
WIRE 16 -1 (1050 3600)(1250 3600);
WIRE 16 -1 (2450 1200)(2450 1300);
WIRE 16 -1 (2450 1300)(2450 1350);
WIRE 16 -1 (2450 1300)(2250 1300);
WIRE 16 -1 (2450 1350)(2450 1400);
WIRE 16 -1 (2450 1350)(2250 1350);
WIRE 16 -1 (2450 1400)(2450 1450);
WIRE 16 -1 (2450 1400)(2250 1400);
WIRE 16 -1 (2450 1450)(2450 1500);
WIRE 16 -1 (2450 1450)(2250 1450);
WIRE 16 -1 (2450 1500)(2450 1550);
WIRE 16 -1 (2450 1500)(2250 1500);
WIRE 16 -1 (2450 1550)(2450 1600);
WIRE 16 -1 (2450 1550)(2250 1550);
WIRE 16 -1 (2450 1600)(2450 1650);
WIRE 16 -1 (2450 1600)(2250 1600);
WIRE 16 -1 (2450 1650)(2450 1700);
WIRE 16 -1 (2450 1650)(2250 1650);
WIRE 16 -1 (2450 1700)(2450 1750);
WIRE 16 -1 (2450 1700)(2250 1700);
WIRE 16 -1 (2450 1750)(2450 1800);
WIRE 16 -1 (2450 1750)(2250 1750);
WIRE 16 -1 (2450 1800)(2450 1850);
WIRE 16 -1 (2450 1800)(2250 1800);
WIRE 16 -1 (2450 1850)(2450 1900);
WIRE 16 -1 (2450 1850)(2250 1850);
WIRE 16 -1 (2450 1900)(2450 1950);
WIRE 16 -1 (2450 1900)(2250 1900);
WIRE 16 -1 (2450 1950)(2450 2000);
WIRE 16 -1 (2450 1950)(2250 1950);
WIRE 16 -1 (2450 2000)(2450 2050);
WIRE 16 -1 (2450 2000)(2250 2000);
WIRE 16 -1 (2450 2050)(2450 2100);
WIRE 16 -1 (2450 2050)(2250 2050);
WIRE 16 -1 (2450 2100)(2450 2150);
WIRE 16 -1 (2450 2100)(2250 2100);
WIRE 16 -1 (2450 2150)(2450 2200);
WIRE 16 -1 (2450 2150)(2250 2150);
WIRE 16 -1 (2450 2200)(2450 2250);
WIRE 16 -1 (2450 2200)(2250 2200);
WIRE 16 -1 (2450 2250)(2450 2300);
WIRE 16 -1 (2450 2250)(2250 2250);
WIRE 16 -1 (2450 2300)(2450 2350);
WIRE 16 -1 (2450 2300)(2250 2300);
WIRE 16 -1 (2450 2350)(2450 2400);
WIRE 16 -1 (2450 2350)(2250 2350);
WIRE 16 -1 (2450 2400)(2450 2450);
WIRE 16 -1 (2450 2400)(2250 2400);
WIRE 16 -1 (2450 2450)(2450 2500);
WIRE 16 -1 (2450 2450)(2250 2450);
WIRE 16 -1 (2450 2500)(2450 2550);
WIRE 16 -1 (2450 2500)(2250 2500);
WIRE 16 -1 (2450 2550)(2450 2600);
WIRE 16 -1 (2450 2550)(2250 2550);
WIRE 16 -1 (2450 2600)(2450 2650);
WIRE 16 -1 (2450 2600)(2250 2600);
WIRE 16 -1 (2450 2650)(2450 2700);
WIRE 16 -1 (2450 2650)(2250 2650);
WIRE 16 -1 (2450 2700)(2450 2750);
WIRE 16 -1 (2450 2700)(2250 2700);
WIRE 16 -1 (2450 2750)(2450 2800);
WIRE 16 -1 (2450 2750)(2250 2750);
WIRE 16 -1 (2450 2800)(2450 2850);
WIRE 16 -1 (2450 2800)(2250 2800);
WIRE 16 -1 (2450 2850)(2450 2900);
WIRE 16 -1 (2450 2850)(2250 2850);
WIRE 16 -1 (2450 2900)(2450 2950);
WIRE 16 -1 (2450 2900)(2250 2900);
WIRE 16 -1 (2450 2950)(2450 3000);
WIRE 16 -1 (2450 2950)(2250 2950);
WIRE 16 -1 (2450 3000)(2450 3050);
WIRE 16 -1 (2450 3000)(2250 3000);
WIRE 16 -1 (2450 3050)(2450 3100);
WIRE 16 -1 (2450 3050)(2250 3050);
WIRE 16 -1 (2450 3100)(2450 3150);
WIRE 16 -1 (2450 3100)(2250 3100);
WIRE 16 -1 (2450 3150)(2450 3200);
WIRE 16 -1 (2450 3150)(2250 3150);
WIRE 16 -1 (2450 3200)(2450 3250);
WIRE 16 -1 (2450 3200)(2250 3200);
WIRE 16 -1 (2450 3250)(2450 3300);
WIRE 16 -1 (2450 3250)(2250 3250);
WIRE 16 -1 (2450 3300)(2450 3350);
WIRE 16 -1 (2450 3300)(2250 3300);
WIRE 16 -1 (2450 3350)(2450 3400);
WIRE 16 -1 (2450 3350)(2250 3350);
WIRE 16 -1 (2450 3400)(2450 3450);
WIRE 16 -1 (2450 3400)(2250 3400);
WIRE 16 -1 (2450 3450)(2450 3500);
WIRE 16 -1 (2450 3450)(2250 3450);
WIRE 16 -1 (2450 3500)(2450 3550);
WIRE 16 -1 (2450 3500)(2250 3500);
WIRE 16 -1 (2450 3550)(2450 3600);
WIRE 16 -1 (2450 3550)(2250 3550);
WIRE 16 -1 (2450 3600)(2250 3600);
WIRE 16 -1 (-5050 1550)(-5050 1450);
WIRE 16 -1 (-3100 1550)(-5050 1550);
WIRE 16 -1 (-3100 1550)(-3100 1500);
WIRE 16 -1 (-2900 1550)(-3100 1550);
WIRE 16 -1 (-3100 1450)(-3100 1500);
WIRE 16 -1 (-3100 1500)(-2900 1500);
WIRE 16 -1 (-3100 1450)(-2900 1450);
WIRE 16 -1 (-4350 950)(-4350 850);
WIRE 16 -1 (-750 2650)(-750 2550);
WIRE 16 -1 (-750 2550)(-750 2500);
WIRE 16 -1 (-750 2550)(-600 2550);
WIRE 16 -1 (-750 2450)(-750 2500);
WIRE 16 -1 (-750 2500)(-600 2500);
WIRE 16 -1 (-750 2400)(-750 2450);
WIRE 16 -1 (-750 2450)(-600 2450);
WIRE 16 -1 (-750 2350)(-750 2400);
WIRE 16 -1 (-750 2400)(-600 2400);
WIRE 16 -1 (-750 2350)(-600 2350);
WIRE 16 -1 (-5050 1700)(-5050 1600);
WIRE 16 -1 (-2900 1600)(-5050 1600);
WIRE 16 -1 (-900 2250)(-900 2350);
WIRE 16 -1 (-900 2250)(-750 2250);
WIRE 16 -1 (-750 2200)(-750 2250);
WIRE 16 -1 (-750 2250)(-600 2250);
WIRE 16 -1 (-600 2200)(-750 2200);
WIRE 16 -1 (600 2550)(600 2725);
WIRE 16 -1 (600 2500)(600 2550);
WIRE 16 -1 (400 2550)(600 2550);
WIRE 16 -1 (400 2500)(600 2500);
WIRE 17 -1 (-3200 2550)(-3750 2550);
FORCEPROP 2 LAST SIG_NAME M_A_ODT<3:0>
J 0
(-3725 2560);
DISPLAY 0.617021 (-3725 2560);
PAINT ORANGE (-3725 2560);
WIRE 17 -1 (-3200 2475)(-3200 2525);
WIRE 17 -1 (-3200 2525)(-3200 2550);
WIRE 17 -1 (-3200 2025)(-3200 2075);
WIRE 17 -1 (-3200 2075)(-3200 2125);
WIRE 17 -1 (-3200 2400)(-3750 2400);
FORCEPROP 2 LAST SIG_NAME M_A_ECC<7:0>
J 0
(-3725 2410);
DISPLAY 0.617021 (-3725 2410);
PAINT ORANGE (-3725 2410);
WIRE 17 -1 (-3200 2125)(-3200 2175);
WIRE 17 -1 (-3200 2175)(-3200 2225);
WIRE 17 -1 (-3200 2375)(-3200 2400);
WIRE 17 -1 (-3200 2325)(-3200 2375);
WIRE 17 -1 (-3200 2225)(-3200 2275);
WIRE 17 -1 (-3200 2275)(-3200 2325);
WIRE 17 -1 (-3200 2700)(-3750 2700);
FORCEPROP 2 LAST SIG_NAME M_A_CKE<3:0>
J 0
(-3725 2710);
DISPLAY 0.617021 (-3725 2710);
PAINT ORANGE (-3725 2710);
WIRE 17 -1 (-3200 2675)(-3200 2700);
WIRE 17 -1 (-3200 2625)(-3200 2675);
WIRE 17 -1 (-1550 1275)(-1550 1325);
WIRE 17 -1 (-1550 1325)(-1550 1375);
WIRE 17 -1 (-1550 1375)(-1550 1425);
WIRE 17 -1 (-1550 1425)(-1550 1475);
WIRE 17 -1 (-1550 1475)(-1550 1525);
WIRE 17 -1 (-1550 1525)(-1550 1575);
WIRE 17 -1 (-1550 1575)(-1550 1625);
WIRE 17 -1 (-1550 1625)(-1550 1675);
WIRE 17 -1 (-1550 1675)(-1550 1725);
WIRE 17 -1 (-1050 4450)(-1550 4450);
FORCEPROP 2 LAST SIG_NAME M_A_DQ<63:0>
J 0
(-1510 4460);
DISPLAY 0.617021 (-1510 4460);
PAINT ORANGE (-1510 4460);
WIRE 17 -1 (-1550 4425)(-1550 4450);
WIRE 17 -1 (-1550 1725)(-1550 1775);
WIRE 17 -1 (-1550 1775)(-1550 1825);
WIRE 17 -1 (-1550 4375)(-1550 4425);
WIRE 17 -1 (-1550 4325)(-1550 4375);
WIRE 17 -1 (-1550 1825)(-1550 1875);
WIRE 17 -1 (-1550 1875)(-1550 1925);
WIRE 17 -1 (-1550 4275)(-1550 4325);
WIRE 17 -1 (-1550 4225)(-1550 4275);
WIRE 17 -1 (-1550 1925)(-1550 1975);
WIRE 17 -1 (-1550 1975)(-1550 2025);
WIRE 17 -1 (-1550 4175)(-1550 4225);
WIRE 17 -1 (-1550 4125)(-1550 4175);
WIRE 17 -1 (-1550 2025)(-1550 2075);
WIRE 17 -1 (-1550 2075)(-1550 2125);
WIRE 17 -1 (-1550 4075)(-1550 4125);
WIRE 17 -1 (-1550 4025)(-1550 4075);
WIRE 17 -1 (-1550 2125)(-1550 2175);
WIRE 17 -1 (-1550 2175)(-1550 2225);
WIRE 17 -1 (-1550 3975)(-1550 4025);
WIRE 17 -1 (-1550 3925)(-1550 3975);
WIRE 17 -1 (-1550 2225)(-1550 2275);
WIRE 17 -1 (-1550 2275)(-1550 2325);
WIRE 17 -1 (-1550 3875)(-1550 3925);
WIRE 17 -1 (-1550 3825)(-1550 3875);
WIRE 17 -1 (-1550 2325)(-1550 2375);
WIRE 17 -1 (-1550 2375)(-1550 2425);
WIRE 17 -1 (-1550 3775)(-1550 3825);
WIRE 17 -1 (-1550 3725)(-1550 3775);
WIRE 17 -1 (-1550 2425)(-1550 2475);
WIRE 17 -1 (-1550 2475)(-1550 2525);
WIRE 17 -1 (-1550 3675)(-1550 3725);
WIRE 17 -1 (-1550 3625)(-1550 3675);
WIRE 17 -1 (-1550 2525)(-1550 2575);
WIRE 17 -1 (-1550 2575)(-1550 2625);
WIRE 17 -1 (-1550 3575)(-1550 3625);
WIRE 17 -1 (-1550 3525)(-1550 3575);
WIRE 17 -1 (-1550 2625)(-1550 2675);
WIRE 17 -1 (-1550 2675)(-1550 2725);
WIRE 17 -1 (-1550 3475)(-1550 3525);
WIRE 17 -1 (-1550 3425)(-1550 3475);
WIRE 17 -1 (-1550 2725)(-1550 2775);
WIRE 17 -1 (-1550 2775)(-1550 2825);
WIRE 17 -1 (-1550 3375)(-1550 3425);
WIRE 17 -1 (-1550 3325)(-1550 3375);
WIRE 17 -1 (-1550 2825)(-1550 2875);
WIRE 17 -1 (-1550 2875)(-1550 2925);
WIRE 17 -1 (-1550 3275)(-1550 3325);
WIRE 17 -1 (-1550 3225)(-1550 3275);
WIRE 17 -1 (-1550 2925)(-1550 2975);
WIRE 17 -1 (-1550 2975)(-1550 3025);
WIRE 17 -1 (-1550 3175)(-1550 3225);
WIRE 17 -1 (-1550 3125)(-1550 3175);
WIRE 17 -1 (-1550 3025)(-1550 3075);
WIRE 17 -1 (-1550 3075)(-1550 3125);
WIRE 17 -1 (-3750 4450)(-3200 4450);
FORCEPROP 2 LAST SIG_NAME M_A_MA<17:0>
J 0
(-3700 4460);
DISPLAY 0.617021 (-3700 4460);
PAINT ORANGE (-3700 4460);
WIRE 17 -1 (-3200 4425)(-3200 4450);
WIRE 17 -1 (-3200 4375)(-3200 4425);
WIRE 17 -1 (-3200 4325)(-3200 4375);
WIRE 17 -1 (-3200 4275)(-3200 4325);
WIRE 17 -1 (-3200 4225)(-3200 4275);
WIRE 17 -1 (-3200 4175)(-3200 4225);
WIRE 17 -1 (-3200 4125)(-3200 4175);
WIRE 17 -1 (-3200 4075)(-3200 4125);
WIRE 17 -1 (-3200 4025)(-3200 4075);
WIRE 17 -1 (-3200 3975)(-3200 4025);
WIRE 17 -1 (-3200 3925)(-3200 3975);
WIRE 17 -1 (-3200 3875)(-3200 3925);
WIRE 17 -1 (-3200 3575)(-3200 3625);
WIRE 17 -1 (-3200 3625)(-3200 3675);
WIRE 17 -1 (-3200 3825)(-3200 3875);
WIRE 17 -1 (-3200 3775)(-3200 3825);
WIRE 17 -1 (-3200 3675)(-3200 3725);
WIRE 17 -1 (-3200 3725)(-3200 3775);
WIRE 17 -1 (900 3175)(900 3275);
WIRE 17 -1 (900 3275)(900 3375);
WIRE 17 -1 (900 3375)(900 3475);
WIRE 17 -1 (900 3475)(900 3575);
WIRE 17 -1 (1500 4900)(900 4900);
FORCEPROP 2 LAST SIG_NAME M_A_DQS_DN<17:0>
J 0
(950 4910);
DISPLAY 0.617021 (950 4910);
PAINT ORANGE (950 4910);
WIRE 17 -1 (900 3575)(900 3675);
WIRE 17 -1 (900 3675)(900 3775);
WIRE 17 -1 (900 4875)(900 4900);
WIRE 17 -1 (900 4775)(900 4875);
WIRE 17 -1 (900 3775)(900 3875);
WIRE 17 -1 (900 3875)(900 3975);
WIRE 17 -1 (900 4675)(900 4775);
WIRE 17 -1 (900 4575)(900 4675);
WIRE 17 -1 (900 3975)(900 4075);
WIRE 17 -1 (900 4075)(900 4175);
WIRE 17 -1 (900 4475)(900 4575);
WIRE 17 -1 (900 4375)(900 4475);
WIRE 17 -1 (900 4175)(900 4275);
WIRE 17 -1 (900 4275)(900 4375);
WIRE 17 -1 (700 3225)(700 3325);
WIRE 17 -1 (700 3325)(700 3425);
WIRE 17 -1 (700 3425)(700 3525);
WIRE 17 -1 (1500 4950)(700 4950);
FORCEPROP 2 LAST SIG_NAME M_A_DQS_DP<17:0>
J 0
(950 4960);
DISPLAY 0.617021 (950 4960);
PAINT ORANGE (950 4960);
WIRE 17 -1 (700 4925)(700 4950);
WIRE 17 -1 (700 3525)(700 3625);
WIRE 17 -1 (700 3625)(700 3725);
WIRE 17 -1 (700 4825)(700 4925);
WIRE 17 -1 (700 4725)(700 4825);
WIRE 17 -1 (700 3725)(700 3825);
WIRE 17 -1 (700 3825)(700 3925);
WIRE 17 -1 (700 4625)(700 4725);
WIRE 17 -1 (700 4525)(700 4625);
WIRE 17 -1 (700 3925)(700 4025);
WIRE 17 -1 (700 4025)(700 4125);
WIRE 17 -1 (700 4425)(700 4525);
WIRE 17 -1 (700 4325)(700 4425);
WIRE 17 -1 (700 4125)(700 4225);
WIRE 17 -1 (700 4225)(700 4325);
WIRE 17 -1 (-3200 2950)(-3750 2950);
FORCEPROP 2 LAST SIG_NAME M_A_CS_N<7:0>
J 0
(-3725 2960);
DISPLAY 0.617021 (-3725 2960);
PAINT ORANGE (-3725 2960);
WIRE 17 -1 (-3200 2925)(-3200 2950);
WIRE 17 -1 (-3200 2875)(-3200 2925);
WIRE 17 -1 (-3200 2825)(-3200 2875);
WIRE 17 -1 (-3200 2775)(-3200 2825);
WIRE 17 -1 (-3200 3500)(-3750 3500);
FORCEPROP 2 LAST SIG_NAME M_A_BA<1:0>
J 0
(-3725 3510);
DISPLAY 0.617021 (-3725 3510);
PAINT ORANGE (-3725 3510);
WIRE 17 -1 (-3200 3500)(-3200 3475);
WIRE 17 -1 (-3200 3425)(-3200 3475);
WIRE 17 -1 (-3200 3400)(-3750 3400);
FORCEPROP 2 LAST SIG_NAME M_A_BG<1:0>
J 0
(-3725 3410);
DISPLAY 0.617021 (-3725 3410);
PAINT ORANGE (-3725 3410);
WIRE 17 -1 (-3200 3375)(-3200 3400);
WIRE 17 -1 (-3200 3325)(-3200 3375);
WIRE 17 -1 (-3400 3200)(-3750 3200);
FORCEPROP 2 LAST SIG_NAME M_A_CLK_DN<3:0>
J 0
(-3725 3210);
DISPLAY 0.617021 (-3725 3210);
PAINT ORANGE (-3725 3210);
WIRE 17 -1 (-3400 3175)(-3400 3200);
WIRE 17 -1 (-3400 3175)(-3400 3075);
WIRE 17 -1 (-3200 3250)(-3750 3250);
FORCEPROP 2 LAST SIG_NAME M_A_CLK_DP<3:0>
J 0
(-3725 3260);
DISPLAY 0.617021 (-3725 3260);
PAINT ORANGE (-3725 3260);
WIRE 17 -1 (-3200 3225)(-3200 3250);
WIRE 17 -1 (-3200 3125)(-3200 3225);
WIRE 16 -1 (-2900 3750)(-3100 3750);
WIRE 16 -1 (600 4300)(400 4300);
WIRE 16 -1 (800 4350)(400 4350);
WIRE 16 -1 (600 4400)(400 4400);
WIRE 16 -1 (800 4450)(400 4450);
WIRE 16 -1 (600 4500)(400 4500);
WIRE 16 -1 (800 4550)(400 4550);
WIRE 16 -1 (600 4600)(400 4600);
WIRE 16 -1 (800 4650)(400 4650);
WIRE 16 -1 (600 4700)(400 4700);
WIRE 16 -1 (800 4750)(400 4750);
WIRE 16 -1 (600 4800)(400 4800);
WIRE 16 -1 (800 4850)(400 4850);
WIRE 16 -1 (600 4100)(400 4100);
WIRE 16 -1 (600 4900)(400 4900);
WIRE 16 -1 (800 3150)(400 3150);
WIRE 16 -1 (600 3200)(400 3200);
WIRE 16 -1 (800 3250)(400 3250);
WIRE 16 -1 (600 3300)(400 3300);
WIRE 16 -1 (600 3400)(400 3400);
WIRE 16 -1 (800 3450)(400 3450);
WIRE 16 -1 (600 3500)(400 3500);
WIRE 16 -1 (800 3550)(400 3550);
WIRE 16 -1 (600 3600)(400 3600);
WIRE 16 -1 (800 3650)(400 3650);
WIRE 16 -1 (600 3700)(400 3700);
WIRE 16 -1 (800 3750)(400 3750);
WIRE 16 -1 (600 3800)(400 3800);
WIRE 16 -1 (800 3850)(400 3850);
WIRE 16 -1 (600 3900)(400 3900);
WIRE 16 -1 (800 3950)(400 3950);
WIRE 16 -1 (600 4000)(400 4000);
WIRE 16 -1 (-1650 4250)(-1900 4250);
WIRE 16 -1 (-1650 4200)(-1900 4200);
WIRE 16 -1 (-1650 4100)(-1900 4100);
WIRE 16 -1 (-1650 4150)(-1900 4150);
WIRE 16 -1 (-1650 4300)(-1900 4300);
WIRE 16 -1 (-1650 4350)(-1900 4350);
WIRE 16 -1 (-1650 4400)(-1900 4400);
WIRE 16 -1 (-2900 4150)(-3100 4150);
WIRE 16 -1 (-2900 4200)(-3100 4200);
WIRE 16 -1 (-2900 4400)(-3100 4400);
WIRE 16 -1 (-2900 4100)(-3100 4100);
WIRE 16 -1 (-2900 4250)(-3100 4250);
WIRE 16 -1 (-2900 4300)(-3100 4300);
WIRE 16 -1 (-2900 4350)(-3100 4350);
WIRE 16 -1 (-1650 3800)(-1900 3800);
WIRE 16 -1 (-1650 4000)(-1900 4000);
WIRE 16 -1 (-1650 3900)(-1900 3900);
WIRE 16 -1 (-1650 3750)(-1900 3750);
WIRE 16 -1 (-1650 3700)(-1900 3700);
WIRE 16 -1 (-1650 3650)(-1900 3650);
WIRE 16 -1 (-1650 3600)(-1900 3600);
WIRE 16 -1 (-1650 3300)(-1900 3300);
WIRE 16 -1 (-1650 3550)(-1900 3550);
WIRE 16 -1 (-1650 3500)(-1900 3500);
WIRE 16 -1 (-1650 3450)(-1900 3450);
WIRE 16 -1 (-1650 3400)(-1900 3400);
WIRE 16 -1 (-1650 3350)(-1900 3350);
WIRE 16 -1 (-1650 3250)(-1900 3250);
WIRE 16 -1 (-1650 3200)(-1900 3200);
WIRE 16 -1 (-1650 3100)(-1900 3100);
WIRE 16 -1 (-1650 3150)(-1900 3150);
WIRE 16 -1 (-1650 2700)(-1900 2700);
WIRE 16 -1 (-1650 2950)(-1900 2950);
WIRE 16 -1 (-1650 2850)(-1900 2850);
WIRE 16 -1 (-1650 2750)(-1900 2750);
WIRE 16 -1 (-1650 2650)(-1900 2650);
WIRE 16 -1 (-1650 2600)(-1900 2600);
WIRE 16 -1 (-1650 2800)(-1900 2800);
WIRE 16 -1 (-1650 2250)(-1900 2250);
WIRE 16 -1 (-1650 2400)(-1900 2400);
WIRE 16 -1 (-1650 2500)(-1900 2500);
WIRE 16 -1 (-1650 2450)(-1900 2450);
WIRE 16 -1 (-1650 2350)(-1900 2350);
WIRE 16 -1 (-1650 2300)(-1900 2300);
WIRE 16 -1 (-1650 2200)(-1900 2200);
WIRE 16 -1 (-1650 2150)(-1900 2150);
WIRE 16 -1 (-1650 2050)(-1900 2050);
WIRE 16 -1 (-1650 2550)(-1900 2550);
WIRE 16 -1 (-1650 2100)(-1900 2100);
WIRE 16 -1 (-1650 1650)(-1900 1650);
WIRE 16 -1 (-1650 1950)(-1900 1950);
WIRE 16 -1 (-1650 1900)(-1900 1900);
WIRE 16 -1 (-1650 1850)(-1900 1850);
WIRE 16 -1 (-1650 1800)(-1900 1800);
WIRE 16 -1 (-1650 1750)(-1900 1750);
WIRE 16 -1 (-1650 1700)(-1900 1700);
WIRE 16 -1 (-1650 1600)(-1900 1600);
WIRE 16 -1 (-1650 1550)(-1900 1550);
WIRE 16 -1 (-1650 2000)(-1900 2000);
WIRE 16 -1 (-1650 1300)(-1900 1300);
WIRE 16 -1 (-1650 1250)(-1900 1250);
WIRE 16 -1 (-1650 1350)(-1900 1350);
WIRE 16 -1 (-1650 1400)(-1900 1400);
WIRE 16 -1 (-1650 1450)(-1900 1450);
WIRE 16 -1 (-1650 1500)(-1900 1500);
WIRE 16 -1 (-3050 2950)(-2900 2950);
WIRE 16 -1 (-3050 3000)(-3750 3000);
FORCEPROP 2 LAST SIG_NAME M_A_C<2>
J 0
(-3700 3010);
DISPLAY 0.617021 (-3700 3010);
PAINT ORANGE (-3700 3010);
WIRE 16 -1 (-3050 3000)(-3050 2950);
WIRE 16 -1 (-2900 3200)(-3100 3200);
WIRE 16 -1 (-2900 2800)(-3100 2800);
WIRE 16 -1 (-2900 3450)(-3100 3450);
WIRE 16 -1 (-2900 3150)(-3300 3150);
WIRE 16 -1 (-2900 3100)(-3100 3100);
WIRE 16 -1 (-2900 2900)(-3100 2900);
WIRE 16 -1 (-2900 2850)(-3100 2850);
WIRE 16 -1 (-2900 3550)(-3100 3550);
WIRE 16 -1 (-2900 3600)(-3100 3600);
WIRE 16 -1 (-2900 3900)(-3100 3900);
WIRE 16 -1 (-2900 3950)(-3100 3950);
WIRE 16 -1 (-2900 2300)(-3100 2300);
WIRE 16 -1 (-2900 2200)(-3100 2200);
WIRE 16 -1 (-2900 2150)(-3100 2150);
WIRE 16 -1 (-2900 2100)(-3100 2100);
WIRE 16 -1 (-2900 2050)(-3100 2050);
WIRE 16 -1 (-2900 3050)(-3300 3050);
WIRE 16 -1 (-2900 2650)(-3100 2650);
WIRE 16 -1 (-2900 3300)(-3100 3300);
WIRE 16 -1 (-2900 3350)(-3100 3350);
WIRE 16 -1 (-2900 3400)(-3100 3400);
WIRE 16 -1 (-2900 3650)(-3100 3650);
WIRE 16 -1 (-2900 4050)(-3100 4050);
WIRE 16 -1 (-2900 2350)(-3100 2350);
WIRE 16 -1 (-2900 1900)(-3250 1900);
WIRE 16 -1 (-3250 1900)(-3250 2350);
WIRE 16 -1 (-3250 2350)(-3750 2350);
FORCEPROP 2 LAST SIG_NAME M_A_PAR
J 0
(-3725 2360);
DISPLAY 0.617021 (-3725 2360);
PAINT ORANGE (-3725 2360);
WIRE 16 -1 (-3350 1800)(-2900 1800);
WIRE 16 -1 (-3350 1800)(-3350 2050);
WIRE 16 -1 (-3350 2050)(-3975 2050);
FORCEPROP 2 LAST SIG_NAME FM_DIMM_EVENT_COD_N
J 0
(-3903 2058);
DISPLAY 0.617021 (-3903 2058);
PAINT ORANGE (-3903 2058);
WIRE 16 -1 (-2900 1850)(-3300 1850);
WIRE 16 -1 (-3300 1850)(-3300 2300);
WIRE 16 -1 (-3300 2300)(-3750 2300);
FORCEPROP 2 LAST SIG_NAME M_ABC_RST_N
J 0
(-3725 2310);
DISPLAY 0.617021 (-3725 2310);
PAINT ORANGE (-3725 2310);
WIRE 16 -1 (-2900 1700)(-3975 1700);
FORCEPROP 2 LAST SIG_NAME M_A_ACT_N
J 0
(-3925 1710);
DISPLAY 0.617021 (-3925 1710);
PAINT ORANGE (-3925 1710);
WIRE 16 -1 (-2900 1750)(-3975 1750);
FORCEPROP 2 LAST SIG_NAME M_A_ALERT_N
J 0
(-3925 1760);
DISPLAY 0.617021 (-3925 1760);
PAINT ORANGE (-3925 1760);
WIRE 16 -1 (-3750 950)(-2900 950);
FORCEPROP 2 LAST SIG_NAME FM_ADR_COMPLETE_ABC_N
J 0
(-3700 960);
DISPLAY 0.617021 (-3700 960);
PAINT ORANGE (-3700 960);
WIRE 16 -1 (-2900 1400)(-3750 1400);
WIRE 16 -1 (-3750 1350)(-2900 1350);
FORCEPROP 2 LAST SIG_NAME SMB_DDR_ABC_VPP_SCL
J 0
(-3710 1360);
DISPLAY 0.617021 (-3710 1360);
PAINT ORANGE (-3710 1360);
WIRE 16 -1 (-2900 2000)(-3100 2000);
WIRE 16 -1 (-3750 1150)(-2900 1150);
FORCEPROP 2 LAST SIG_NAME TP_CH_A_DIMM_A0_RFU_2
J 0
(-3700 1160);
DISPLAY 0.617021 (-3700 1160);
PAINT ORANGE (-3700 1160);
FORCEPROP 2 LASTPROP $XRERR UNIQUE?
J 0
(-3990 1150);
DISPLAY 0.638298 (-3990 1150);
PAINT MONO (-3990 1150);
DISPLAY INVISIBLE (-3990 1150);
WIRE 16 -1 (-3750 1050)(-2900 1050);
FORCEPROP 2 LAST SIG_NAME TP_CH_A_DIMM_A0_RFU_0
J 0
(-3700 1060);
DISPLAY 0.617021 (-3700 1060);
PAINT ORANGE (-3700 1060);
FORCEPROP 2 LASTPROP $XRERR UNIQUE?
J 0
(-3990 1050);
DISPLAY 0.638298 (-3990 1050);
PAINT MONO (-3990 1050);
DISPLAY INVISIBLE (-3990 1050);
WIRE 16 -1 (-3750 1100)(-2900 1100);
FORCEPROP 2 LAST SIG_NAME TP_CH_A_DIMM_A0_RFU_1
J 0
(-3700 1110);
DISPLAY 0.617021 (-3700 1110);
PAINT ORANGE (-3700 1110);
FORCEPROP 2 LASTPROP $XRERR UNIQUE?
J 0
(-3990 1100);
DISPLAY 0.638298 (-3990 1100);
PAINT MONO (-3990 1100);
DISPLAY INVISIBLE (-3990 1100);
WIRE 16 -1 (-2900 4000)(-3100 4000);
WIRE 16 -1 (-1650 3950)(-1900 3950);
WIRE 16 -1 (800 3350)(400 3350);
WIRE 16 -1 (-1650 2900)(-1900 2900);
WIRE 16 -1 (-2900 2750)(-3100 2750);
WIRE 16 -1 (-4450 1250)(-4350 1250);
WIRE 16 -1 (-4350 1150)(-4350 1250);
WIRE 16 -1 (-2900 1250)(-4350 1250);
FORCEPROP 2 LAST SIG_NAME M_A_VREF
J 0
(-3700 1260);
DISPLAY 0.617021 (-3700 1260);
PAINT ORANGE (-3700 1260);
WIRE 16 -1 (-1650 4050)(-1900 4050);
WIRE 16 -1 (-1650 3000)(-1900 3000);
WIRE 16 -1 (-1650 3850)(-1900 3850);
WIRE 16 -1 (800 4050)(400 4050);
WIRE 16 -1 (800 4150)(400 4150);
WIRE 16 -1 (600 4200)(400 4200);
WIRE 16 -1 (800 4250)(400 4250);
WIRE 16 -1 (-2900 3850)(-3100 3850);
WIRE 16 -1 (-2900 3800)(-3100 3800);
WIRE 16 -1 (-2900 3700)(-3100 3700);
WIRE 16 -1 (-1650 3050)(-1900 3050);
WIRE 16 -1 (-2900 2600)(-3100 2600);
WIRE 16 -1 (-2900 2250)(-3100 2250);
WIRE 16 -1 (-2900 2450)(-3100 2450);
WIRE 16 -1 (-2900 2500)(-3100 2500);
DOT 1 (1050 1700);
DOT 1 (-750 1950);
DOT 1 (1050 3200);
DOT 1 (-3100 1550);
DOT 1 (-750 1200);
DOT 1 (-750 1150);
DOT 1 (-750 1350);
DOT 1 (-750 2450);
DOT 1 (-750 2100);
DOT 1 (1050 2550);
DOT 1 (1050 2050);
DOT 1 (600 2550);
DOT 1 (1050 2350);
DOT 1 (1050 2250);
DOT 1 (1050 2200);
DOT 1 (1050 2150);
DOT 1 (2450 3500);
DOT 1 (2450 3450);
DOT 1 (2450 3400);
DOT 1 (2450 3250);
DOT 1 (2450 3350);
DOT 1 (2450 3300);
DOT 1 (2450 3200);
DOT 1 (2450 3150);
DOT 1 (2450 3100);
DOT 1 (2450 3000);
DOT 1 (2450 3050);
DOT 1 (2450 2900);
DOT 1 (2450 2950);
DOT 1 (2450 2850);
DOT 1 (2450 2800);
DOT 1 (2450 2750);
DOT 1 (2450 2650);
DOT 1 (2450 2700);
DOT 1 (2450 2600);
DOT 1 (2450 2550);
DOT 1 (2450 2500);
DOT 1 (2450 2350);
DOT 1 (2450 2450);
DOT 1 (2450 2400);
DOT 1 (2450 2300);
DOT 1 (2450 2250);
DOT 1 (2450 2100);
DOT 1 (2450 2200);
DOT 1 (2450 2150);
DOT 1 (2450 2000);
DOT 1 (2450 2050);
DOT 1 (2450 1950);
DOT 1 (2450 1900);
DOT 1 (2450 1850);
DOT 1 (2450 1750);
DOT 1 (2450 1800);
DOT 1 (2450 1700);
DOT 1 (2450 1650);
DOT 1 (2450 1600);
DOT 1 (2450 1550);
DOT 1 (2450 1500);
DOT 1 (2450 1450);
DOT 1 (2450 1400);
DOT 1 (2450 1300);
DOT 1 (1050 3550);
DOT 1 (1050 3500);
DOT 1 (1050 3450);
DOT 1 (1050 3400);
DOT 1 (1050 3250);
DOT 1 (1050 3300);
DOT 1 (1050 3350);
DOT 1 (1050 3150);
DOT 1 (1050 3100);
DOT 1 (1050 3000);
DOT 1 (1050 3050);
DOT 1 (1050 2900);
DOT 1 (1050 2950);
DOT 1 (1050 2850);
DOT 1 (1050 2750);
DOT 1 (1050 2650);
DOT 1 (1050 2700);
DOT 1 (1050 2600);
DOT 1 (1050 2400);
DOT 1 (1050 2450);
DOT 1 (1050 2300);
DOT 1 (1050 2100);
DOT 1 (1050 2000);
DOT 1 (1050 1950);
DOT 1 (1050 1900);
DOT 1 (1050 1850);
DOT 1 (1050 1750);
DOT 1 (1050 1800);
DOT 1 (1050 1650);
DOT 1 (1050 1600);
DOT 1 (1050 1450);
DOT 1 (1050 1400);
DOT 1 (1050 1350);
DOT 1 (1050 1300);
DOT 1 (-750 1850);
DOT 1 (-750 1800);
DOT 1 (-750 1700);
DOT 1 (-750 1650);
DOT 1 (-750 1600);
DOT 1 (-750 1550);
DOT 1 (-750 1500);
DOT 1 (-750 1450);
DOT 1 (-750 1400);
DOT 1 (-750 1250);
DOT 1 (-750 1100);
DOT 1 (-750 1050);
DOT 1 (-750 950);
DOT 1 (-750 900);
DOT 1 (1050 1550);
DOT 1 (1050 1500);
DOT 1 (-750 2250);
DOT 1 (2450 1350);
DOT 1 (-750 2550);
DOT 1 (-750 2400);
DOT 1 (1050 2800);
DOT 1 (1050 2500);
DOT 1 (-3100 1500);
DOT 1 (-750 1300);
DOT 1 (-750 1000);
DOT 1 (-750 2500);
DOT 1 (-750 2050);
DOT 1 (-750 2000);
DOT 1 (-750 1900);
DOT 1 (-4350 1250);
DOT 1 (2450 3550);
DOT 1 (-750 1750);
FORCENOTE
PVPP CAP: 10UF X12
(-3950 4900) 0;
DISPLAY LEFT (-3950 4900);
DISPLAY 1.021277 (-3950 4900);
PAINT PURPLE (-3950 4900);
FORCENOTE
PVTT CAP: 100UF X2, 47UF X1
(-3950 4850) 0;
DISPLAY LEFT (-3950 4850);
DISPLAY 1.021277 (-3950 4850);
PAINT PURPLE (-3950 4850);
FORCENOTE
CAP BETWEEN DIMM
(-3950 4975) 0;
DISPLAY LEFT (-3950 4975);
DISPLAY 1.276596 (-3950 4975);
PAINT PURPLE (-3950 4975);
FORCENOTE
PVDDQ (DOUBLE SIDE) CAP: 100UF X8, 47UF X41
(-3950 4750) 0;
DISPLAY LEFT (-3950 4750);
DISPLAY 1.021277 (-3950 4750);
PAINT PURPLE (-3950 4750);
FORCENOTE
PVDDQ (SINGLE SIDE) CAP: 10UF X1, 22UF X50
(-3950 4800) 0;
DISPLAY LEFT (-3950 4800);
DISPLAY 1.021277 (-3950 4800);
PAINT PURPLE (-3950 4800);
FORCENOTE
SMBUS ADDR: 0XA0
(-5300 525) 0;
DISPLAY LEFT (-5300 525);
DISPLAY 1.361702 (-5300 525);
PAINT PURPLE (-5300 525);
FORCENOTE
ROOM = DDR4_CH_A
(-5300 425) 0;
DISPLAY LEFT (-5300 425);
DISPLAY 1.361702 (-5300 425);
PAINT PURPLE (-5300 425);
FORCENOTE
PLACE CAP NEAR DIMM CONNECTOR
(-4304 800) 0;
DISPLAY LEFT (-4304 800);
DISPLAY 1.021277 (-4304 800);
PAINT PURPLE (-4304 800);
QUIT
